FILE_TYPE = MACRO_DRAWING;
SET COLOR_WIRE YELLOW;
SET COLOR_PROP MONO;
SET COLOR_DOT WHITE;
SET COLOR_ARC YELLOW;
SET COLOR_BODY GREEN;
SET COLOR_NOTE MONO;
SET PROP_DISPLAY VALUE;
SET PAGE_NUMBER P116;
FORCEADD OFFPAGE..1
(-7200 2900);
FORCEPROP 2 LAST $XR0 172 
J 0
(-7452 2900);
DISPLAY 0.638298 (-7452 2900);
PAINT MONO (-7452 2900);
FORCEPROP 2 LAST CDS_LIB mstr_standard
J 0
(-7200 2900);
PAINT ORANGE (-7200 2900);
DISPLAY INVISIBLE (-7200 2900);
FORCEPROP 1 LAST COMMENT_BODY TRUE
J 0
(-7075 2800);
DISPLAY 1.170213 (-7075 2800);
PAINT PEACH (-7075 2800);
DISPLAY INVISIBLE (-7075 2800);
FORCEPROP 2 LAST PATH I101
J 0
(-7150 2975);
DISPLAY 1.361702 (-7150 2975);
PAINT ORANGE (-7150 2975);
DISPLAY INVISIBLE (-7150 2975);
FORCEPROP 1 LAST OFFPAGE TRUE
J 0
(-6875 2775);
PAINT GREEN (-6875 2775);
DISPLAY INVISIBLE (-6875 2775);
FORCEADD OFFPAGE..1
(-7200 2700);
FORCEPROP 2 LAST $XR0 139 
J 0
(-7452 2700);
DISPLAY 0.638298 (-7452 2700);
PAINT MONO (-7452 2700);
FORCEPROP 2 LAST CDS_LIB mstr_standard
J 0
(-7200 2700);
PAINT ORANGE (-7200 2700);
DISPLAY INVISIBLE (-7200 2700);
FORCEPROP 1 LAST COMMENT_BODY TRUE
J 0
(-7075 2600);
DISPLAY 1.170213 (-7075 2600);
PAINT PEACH (-7075 2600);
DISPLAY INVISIBLE (-7075 2600);
FORCEPROP 2 LAST PATH I102
J 0
(-7150 2775);
DISPLAY 1.361702 (-7150 2775);
PAINT ORANGE (-7150 2775);
DISPLAY INVISIBLE (-7150 2775);
FORCEPROP 1 LAST OFFPAGE TRUE
J 0
(-6875 2575);
PAINT GREEN (-6875 2575);
DISPLAY INVISIBLE (-6875 2575);
FORCEADD OFFPAGE..1
(-7200 2750);
FORCEPROP 2 LAST $XR0 139 
J 0
(-7452 2750);
DISPLAY 0.638298 (-7452 2750);
PAINT MONO (-7452 2750);
FORCEPROP 2 LAST CDS_LIB mstr_standard
J 0
(-7200 2750);
PAINT ORANGE (-7200 2750);
DISPLAY INVISIBLE (-7200 2750);
FORCEPROP 1 LAST COMMENT_BODY TRUE
J 0
(-7075 2650);
DISPLAY 1.170213 (-7075 2650);
PAINT PEACH (-7075 2650);
DISPLAY INVISIBLE (-7075 2650);
FORCEPROP 2 LAST PATH I103
J 0
(-7150 2825);
DISPLAY 1.361702 (-7150 2825);
PAINT ORANGE (-7150 2825);
DISPLAY INVISIBLE (-7150 2825);
FORCEPROP 1 LAST OFFPAGE TRUE
J 0
(-6875 2625);
PAINT GREEN (-6875 2625);
DISPLAY INVISIBLE (-6875 2625);
FORCEADD OFFPAGE..1
(-7200 2850);
FORCEPROP 2 LAST $XR0 185 
J 0
(-7452 2850);
DISPLAY 0.638298 (-7452 2850);
PAINT MONO (-7452 2850);
FORCEPROP 2 LAST CDS_LIB mstr_standard
J 0
(-7200 2850);
PAINT ORANGE (-7200 2850);
DISPLAY INVISIBLE (-7200 2850);
FORCEPROP 1 LAST COMMENT_BODY TRUE
J 0
(-7075 2750);
DISPLAY 1.170213 (-7075 2750);
PAINT PEACH (-7075 2750);
DISPLAY INVISIBLE (-7075 2750);
FORCEPROP 2 LAST PATH I104
J 0
(-7150 2925);
DISPLAY 1.361702 (-7150 2925);
PAINT ORANGE (-7150 2925);
DISPLAY INVISIBLE (-7150 2925);
FORCEPROP 1 LAST OFFPAGE TRUE
J 0
(-6875 2725);
PAINT GREEN (-6875 2725);
DISPLAY INVISIBLE (-6875 2725);
FORCEADD OFFPAGE..1
(-7200 2800);
FORCEPROP 2 LAST $XR0 185 
J 0
(-7452 2800);
DISPLAY 0.638298 (-7452 2800);
PAINT MONO (-7452 2800);
FORCEPROP 2 LAST CDS_LIB mstr_standard
J 0
(-7200 2800);
PAINT ORANGE (-7200 2800);
DISPLAY INVISIBLE (-7200 2800);
FORCEPROP 1 LAST COMMENT_BODY TRUE
J 0
(-7075 2700);
DISPLAY 1.170213 (-7075 2700);
PAINT PEACH (-7075 2700);
DISPLAY INVISIBLE (-7075 2700);
FORCEPROP 2 LAST PATH I105
J 0
(-7150 2875);
DISPLAY 1.361702 (-7150 2875);
PAINT ORANGE (-7150 2875);
DISPLAY INVISIBLE (-7150 2875);
FORCEPROP 1 LAST OFFPAGE TRUE
J 0
(-6875 2675);
PAINT GREEN (-6875 2675);
DISPLAY INVISIBLE (-6875 2675);
FORCEADD OFFPAGE..1
(-7200 2650);
FORCEPROP 2 LAST $XR0 145 
J 0
(-7452 2650);
DISPLAY 0.638298 (-7452 2650);
PAINT MONO (-7452 2650);
FORCEPROP 2 LAST $XR1 116 
J 0
(-7572 2650);
DISPLAY 0.638298 (-7572 2650);
PAINT MONO (-7572 2650);
FORCEPROP 2 LAST CDS_LIB mstr_standard
J 0
(-7200 2650);
PAINT ORANGE (-7200 2650);
DISPLAY INVISIBLE (-7200 2650);
FORCEPROP 1 LAST COMMENT_BODY TRUE
J 0
(-7075 2550);
DISPLAY 1.170213 (-7075 2550);
PAINT PEACH (-7075 2550);
DISPLAY INVISIBLE (-7075 2550);
FORCEPROP 1 LAST OFFPAGE TRUE
J 0
(-6875 2525);
PAINT GREEN (-6875 2525);
DISPLAY INVISIBLE (-6875 2525);
FORCEPROP 2 LAST PATH I106
J 0
(-7150 2725);
DISPLAY 1.361702 (-7150 2725);
PAINT ORANGE (-7150 2725);
DISPLAY INVISIBLE (-7150 2725);
FORCEADD OFFPAGE..1
(-7200 2600);
FORCEPROP 2 LAST $XR0 145 
J 0
(-7452 2600);
DISPLAY 0.638298 (-7452 2600);
PAINT MONO (-7452 2600);
FORCEPROP 2 LAST $XR1 116 
J 0
(-7572 2600);
DISPLAY 0.638298 (-7572 2600);
PAINT MONO (-7572 2600);
FORCEPROP 2 LAST CDS_LIB mstr_standard
J 0
(-7200 2600);
PAINT ORANGE (-7200 2600);
DISPLAY INVISIBLE (-7200 2600);
FORCEPROP 1 LAST COMMENT_BODY TRUE
J 0
(-7075 2500);
DISPLAY 1.170213 (-7075 2500);
PAINT PEACH (-7075 2500);
DISPLAY INVISIBLE (-7075 2500);
FORCEPROP 1 LAST OFFPAGE TRUE
J 0
(-6875 2475);
PAINT GREEN (-6875 2475);
DISPLAY INVISIBLE (-6875 2475);
FORCEPROP 2 LAST PATH I107
J 0
(-7150 2675);
DISPLAY 1.361702 (-7150 2675);
PAINT ORANGE (-7150 2675);
DISPLAY INVISIBLE (-7150 2675);
FORCEADD RES..2
R 2
(-7550 2150);
FORCEPROP 1 LAST PACK_TYPE 0402
J 2
(-7590 1975);
DISPLAY 0.617021 (-7590 1975);
PAINT SKYBLUE (-7590 1975);
FORCEPROP 1 LAST PART_NUMBER G21796-017
J 2
(-7590 2025);
DISPLAY 0.617021 (-7590 2025);
PAINT BLUE (-7590 2025);
FORCEPROP 1 LAST LOCATION R3M11
J 2
(-7595 2275);
DISPLAY 0.617021 (-7595 2275);
PAINT AQUA (-7595 2275);
FORCEPROP 1 LAST VALUE 100.0
J 2
(-7595 2225);
DISPLAY 0.617021 (-7595 2225);
PAINT SKYBLUE (-7595 2225);
FORCEPROP 1 LAST MATERIAL CHIP
J 2
(-7590 2075);
DISPLAY 0.617021 (-7590 2075);
PAINT SKYBLUE (-7590 2075);
FORCEPROP 1 LAST WATTAGE 1/16W
J 2
(-7590 2125);
DISPLAY 0.617021 (-7590 2125);
PAINT SKYBLUE (-7590 2125);
FORCEPROP 1 LAST TOLERANCE 1%
J 2
(-7595 2175);
DISPLAY 0.617021 (-7595 2175);
PAINT SKYBLUE (-7595 2175);
FORCEPROP 1 LASTPIN (-7550 2250) $PN 1
J 2
(-7555 2212);
DISPLAY 0.617021 (-7555 2212);
PAINT WHITE (-7555 2212);
FORCEPROP 1 LASTPIN (-7550 2050) $PN 2
J 2
(-7555 2060);
DISPLAY 0.617021 (-7555 2060);
PAINT WHITE (-7555 2060);
FORCEPROP 2 LAST CDS_LOCATION R3M11
J 2
(-7595 2275);
DISPLAY 0.617021 (-7595 2275);
PAINT AQUA (-7595 2275);
DISPLAY INVISIBLE (-7595 2275);
FORCEPROP 2 LAST CDS_LIB mstr_discrete
J 0
(-7550 2150);
PAINT ORANGE (-7550 2150);
DISPLAY INVISIBLE (-7550 2150);
FORCEPROP 1 LAST PATH I108
J 2
(-7600 2325);
DISPLAY 0.978723 (-7600 2325);
PAINT WHITE (-7600 2325);
DISPLAY INVISIBLE (-7600 2325);
FORCEPROP 2 LAST SEC_TYPE 0402
J 0
(-7600 2375);
DISPLAY 1.021277 (-7600 2375);
PAINT ORANGE (-7600 2375);
DISPLAY INVISIBLE (-7600 2375);
FORCEPROP 0 LAST ROOM SB
J 2
(-7600 2375);
DISPLAY 1.021277 (-7600 2375);
PAINT ORANGE (-7600 2375);
DISPLAY INVISIBLE (-7600 2375);
FORCEPROP 2 LAST NO_XNET_CONNECTION 1
J 0
(-7600 2375);
PAINT MONO (-7600 2375);
DISPLAY INVISIBLE (-7600 2375);
FORCEPROP 2 LAST SEC 1
J 0
(-7600 2375);
DISPLAY 0.680851 (-7600 2375);
PAINT MONO (-7600 2375);
DISPLAY INVISIBLE (-7600 2375);
FORCEADD TAP..1
(-1875 3900);
FORCEPROP 3 LASTPIN (-1925 3900) SIG_NAME SATA6G_PCH_PCIE_UP_SATA_TXN<5>
J 0
(-1915 3910);
DISPLAY 0.659574 (-1915 3910);
PAINT MONO (-1915 3910);
DISPLAY INVISIBLE (-1915 3910);
FORCEPROP 1 LASTPIN (-1925 3900) BN 5
J 0
(-1937 3908);
DISPLAY 0.617021 (-1937 3908);
PAINT GREEN (-1937 3908);
FORCEPROP 2 LAST CDS_LIB mstr_standard
J 0
(-1875 3900);
PAINT ORANGE (-1875 3900);
DISPLAY INVISIBLE (-1875 3900);
FORCEPROP 1 LAST PATH I122
J 0
(-1877 3900);
DISPLAY 0.872340 (-1877 3900);
PAINT GREEN (-1877 3900);
DISPLAY INVISIBLE (-1877 3900);
FORCEPROP 1 LAST BODY_TYPE PLUMBING
J 0
(-1875 3950);
DISPLAY 1.446809 (-1875 3950);
PAINT GREEN (-1875 3950);
DISPLAY INVISIBLE (-1875 3950);
FORCEPROP 1 LAST HDL_TAP TRUE
J 0
(-1550 3775);
DISPLAY 1.446809 (-1550 3775);
PAINT GREEN (-1550 3775);
DISPLAY INVISIBLE (-1550 3775);
FORCEADD TAP..1
(-1875 3800);
FORCEPROP 3 LASTPIN (-1925 3800) SIG_NAME SATA6G_PCH_PCIE_UP_SATA_TXN<4>
J 0
(-1915 3810);
DISPLAY 0.659574 (-1915 3810);
PAINT MONO (-1915 3810);
DISPLAY INVISIBLE (-1915 3810);
FORCEPROP 1 LASTPIN (-1925 3800) BN 4
J 0
(-1937 3808);
DISPLAY 0.617021 (-1937 3808);
PAINT GREEN (-1937 3808);
FORCEPROP 1 LAST PATH I123
J 0
(-1877 3800);
DISPLAY 0.872340 (-1877 3800);
PAINT GREEN (-1877 3800);
DISPLAY INVISIBLE (-1877 3800);
FORCEPROP 2 LAST CDS_LIB mstr_standard
J 0
(-1875 3800);
PAINT ORANGE (-1875 3800);
DISPLAY INVISIBLE (-1875 3800);
FORCEPROP 1 LAST BODY_TYPE PLUMBING
J 0
(-1875 3850);
DISPLAY 1.446809 (-1875 3850);
PAINT GREEN (-1875 3850);
DISPLAY INVISIBLE (-1875 3850);
FORCEPROP 1 LAST HDL_TAP TRUE
J 0
(-1550 3675);
DISPLAY 1.446809 (-1550 3675);
PAINT GREEN (-1550 3675);
DISPLAY INVISIBLE (-1550 3675);
FORCEADD TAP..1
(-2025 4150);
FORCEPROP 3 LASTPIN (-2075 4150) SIG_NAME SATA6G_PCH_PCIE_UP_SATA_TXP<7>
J 0
(-2065 4160);
DISPLAY 0.659574 (-2065 4160);
PAINT MONO (-2065 4160);
DISPLAY INVISIBLE (-2065 4160);
FORCEPROP 1 LASTPIN (-2075 4150) BN 7
J 0
(-2087 4158);
DISPLAY 0.617021 (-2087 4158);
PAINT GREEN (-2087 4158);
FORCEPROP 1 LAST HDL_TAP TRUE
J 0
(-1700 4025);
DISPLAY 1.446809 (-1700 4025);
PAINT GREEN (-1700 4025);
DISPLAY INVISIBLE (-1700 4025);
FORCEPROP 1 LAST PATH I125
J 0
(-2027 4150);
DISPLAY 0.872340 (-2027 4150);
PAINT GREEN (-2027 4150);
DISPLAY INVISIBLE (-2027 4150);
FORCEPROP 1 LAST BODY_TYPE PLUMBING
J 0
(-2025 4200);
DISPLAY 1.446809 (-2025 4200);
PAINT GREEN (-2025 4200);
DISPLAY INVISIBLE (-2025 4200);
FORCEPROP 2 LAST CDS_LIB mstr_standard
J 0
(-2025 4150);
PAINT ORANGE (-2025 4150);
DISPLAY INVISIBLE (-2025 4150);
FORCEADD TAP..1
(-2025 4050);
FORCEPROP 3 LASTPIN (-2075 4050) SIG_NAME SATA6G_PCH_PCIE_UP_SATA_TXP<6>
J 0
(-2065 4060);
DISPLAY 0.659574 (-2065 4060);
PAINT MONO (-2065 4060);
DISPLAY INVISIBLE (-2065 4060);
FORCEPROP 1 LASTPIN (-2075 4050) BN 6
J 0
(-2087 4058);
DISPLAY 0.617021 (-2087 4058);
PAINT GREEN (-2087 4058);
FORCEPROP 1 LAST PATH I128
J 0
(-2027 4050);
DISPLAY 0.872340 (-2027 4050);
PAINT GREEN (-2027 4050);
DISPLAY INVISIBLE (-2027 4050);
FORCEPROP 2 LAST CDS_LIB mstr_standard
J 0
(-2025 4050);
PAINT ORANGE (-2025 4050);
DISPLAY INVISIBLE (-2025 4050);
FORCEPROP 1 LAST HDL_TAP TRUE
J 0
(-1700 3925);
DISPLAY 1.446809 (-1700 3925);
PAINT GREEN (-1700 3925);
DISPLAY INVISIBLE (-1700 3925);
FORCEPROP 1 LAST BODY_TYPE PLUMBING
J 0
(-2025 4100);
DISPLAY 1.446809 (-2025 4100);
PAINT GREEN (-2025 4100);
DISPLAY INVISIBLE (-2025 4100);
FORCEADD TAP..1
(-1875 4000);
FORCEPROP 3 LASTPIN (-1925 4000) SIG_NAME SATA6G_PCH_PCIE_UP_SATA_TXN<6>
J 0
(-1915 4010);
DISPLAY 0.659574 (-1915 4010);
PAINT MONO (-1915 4010);
DISPLAY INVISIBLE (-1915 4010);
FORCEPROP 1 LASTPIN (-1925 4000) BN 6
J 0
(-1937 4008);
DISPLAY 0.617021 (-1937 4008);
PAINT GREEN (-1937 4008);
FORCEPROP 2 LAST CDS_LIB mstr_standard
J 0
(-1875 4000);
PAINT ORANGE (-1875 4000);
DISPLAY INVISIBLE (-1875 4000);
FORCEPROP 1 LAST PATH I129
J 0
(-1877 4000);
DISPLAY 0.872340 (-1877 4000);
PAINT GREEN (-1877 4000);
DISPLAY INVISIBLE (-1877 4000);
FORCEPROP 1 LAST HDL_TAP TRUE
J 0
(-1550 3875);
DISPLAY 1.446809 (-1550 3875);
PAINT GREEN (-1550 3875);
DISPLAY INVISIBLE (-1550 3875);
FORCEPROP 1 LAST BODY_TYPE PLUMBING
J 0
(-1875 4050);
DISPLAY 1.446809 (-1875 4050);
PAINT GREEN (-1875 4050);
DISPLAY INVISIBLE (-1875 4050);
FORCEADD TAP..1
(-1875 4100);
FORCEPROP 3 LASTPIN (-1925 4100) SIG_NAME SATA6G_PCH_PCIE_UP_SATA_TXN<7>
J 0
(-1915 4110);
DISPLAY 0.659574 (-1915 4110);
PAINT MONO (-1915 4110);
DISPLAY INVISIBLE (-1915 4110);
FORCEPROP 1 LASTPIN (-1925 4100) BN 7
J 0
(-1937 4108);
DISPLAY 0.617021 (-1937 4108);
PAINT GREEN (-1937 4108);
FORCEPROP 1 LAST HDL_TAP TRUE
J 0
(-1550 3975);
DISPLAY 1.446809 (-1550 3975);
PAINT GREEN (-1550 3975);
DISPLAY INVISIBLE (-1550 3975);
FORCEPROP 1 LAST PATH I130
J 0
(-1877 4100);
DISPLAY 0.872340 (-1877 4100);
PAINT GREEN (-1877 4100);
DISPLAY INVISIBLE (-1877 4100);
FORCEPROP 1 LAST BODY_TYPE PLUMBING
J 0
(-1875 4150);
DISPLAY 1.446809 (-1875 4150);
PAINT GREEN (-1875 4150);
DISPLAY INVISIBLE (-1875 4150);
FORCEPROP 2 LAST CDS_LIB mstr_standard
J 0
(-1875 4100);
PAINT ORANGE (-1875 4100);
DISPLAY INVISIBLE (-1875 4100);
FORCEADD TAP..1
(-1875 3700);
FORCEPROP 3 LASTPIN (-1925 3700) SIG_NAME SATA6G_PCH_PCIE_UP_SATA_TXN<3>
J 0
(-1915 3710);
DISPLAY 0.659574 (-1915 3710);
PAINT MONO (-1915 3710);
DISPLAY INVISIBLE (-1915 3710);
FORCEPROP 1 LASTPIN (-1925 3700) BN 3
J 0
(-1937 3708);
DISPLAY 0.617021 (-1937 3708);
PAINT GREEN (-1937 3708);
FORCEPROP 1 LAST HDL_TAP TRUE
J 0
(-1550 3575);
DISPLAY 1.446809 (-1550 3575);
PAINT GREEN (-1550 3575);
DISPLAY INVISIBLE (-1550 3575);
FORCEPROP 1 LAST PATH I131
J 0
(-1877 3700);
DISPLAY 0.872340 (-1877 3700);
PAINT GREEN (-1877 3700);
DISPLAY INVISIBLE (-1877 3700);
FORCEPROP 2 LAST CDS_LIB mstr_standard
J 0
(-1875 3700);
PAINT ORANGE (-1875 3700);
DISPLAY INVISIBLE (-1875 3700);
FORCEPROP 1 LAST BODY_TYPE PLUMBING
J 0
(-1875 3750);
DISPLAY 1.446809 (-1875 3750);
PAINT GREEN (-1875 3750);
DISPLAY INVISIBLE (-1875 3750);
FORCEADD TAP..1
(-1875 3600);
FORCEPROP 3 LASTPIN (-1925 3600) SIG_NAME SATA6G_PCH_PCIE_UP_SATA_TXN<2>
J 0
(-1915 3610);
DISPLAY 0.659574 (-1915 3610);
PAINT MONO (-1915 3610);
DISPLAY INVISIBLE (-1915 3610);
FORCEPROP 1 LASTPIN (-1925 3600) BN 2
J 0
(-1937 3608);
DISPLAY 0.617021 (-1937 3608);
PAINT GREEN (-1937 3608);
FORCEPROP 1 LAST HDL_TAP TRUE
J 0
(-1550 3475);
DISPLAY 1.446809 (-1550 3475);
PAINT GREEN (-1550 3475);
DISPLAY INVISIBLE (-1550 3475);
FORCEPROP 2 LAST CDS_LIB mstr_standard
J 0
(-1875 3600);
PAINT ORANGE (-1875 3600);
DISPLAY INVISIBLE (-1875 3600);
FORCEPROP 1 LAST BODY_TYPE PLUMBING
J 0
(-1875 3650);
DISPLAY 1.446809 (-1875 3650);
PAINT GREEN (-1875 3650);
DISPLAY INVISIBLE (-1875 3650);
FORCEPROP 1 LAST PATH I132
J 0
(-1877 3600);
DISPLAY 0.872340 (-1877 3600);
PAINT GREEN (-1877 3600);
DISPLAY INVISIBLE (-1877 3600);
FORCEADD TAP..1
(-1875 3500);
FORCEPROP 3 LASTPIN (-1925 3500) SIG_NAME SATA6G_PCH_PCIE_UP_SATA_TXN<1>
J 0
(-1915 3510);
DISPLAY 0.659574 (-1915 3510);
PAINT MONO (-1915 3510);
DISPLAY INVISIBLE (-1915 3510);
FORCEPROP 1 LASTPIN (-1925 3500) BN 1
J 0
(-1937 3508);
DISPLAY 0.617021 (-1937 3508);
PAINT GREEN (-1937 3508);
FORCEPROP 2 LAST CDS_LIB mstr_standard
J 0
(-1875 3500);
PAINT ORANGE (-1875 3500);
DISPLAY INVISIBLE (-1875 3500);
FORCEPROP 1 LAST PATH I133
J 0
(-1877 3500);
DISPLAY 0.872340 (-1877 3500);
PAINT GREEN (-1877 3500);
DISPLAY INVISIBLE (-1877 3500);
FORCEPROP 1 LAST HDL_TAP TRUE
J 0
(-1550 3375);
DISPLAY 1.446809 (-1550 3375);
PAINT GREEN (-1550 3375);
DISPLAY INVISIBLE (-1550 3375);
FORCEPROP 1 LAST BODY_TYPE PLUMBING
J 0
(-1875 3550);
DISPLAY 1.446809 (-1875 3550);
PAINT GREEN (-1875 3550);
DISPLAY INVISIBLE (-1875 3550);
FORCEADD TAP..1
(-1875 3400);
FORCEPROP 3 LASTPIN (-1925 3400) SIG_NAME SATA6G_PCH_PCIE_UP_SATA_TXN<0>
J 0
(-1915 3410);
DISPLAY 0.659574 (-1915 3410);
PAINT MONO (-1915 3410);
DISPLAY INVISIBLE (-1915 3410);
FORCEPROP 1 LASTPIN (-1925 3400) BN 0
J 0
(-1937 3408);
DISPLAY 0.617021 (-1937 3408);
PAINT GREEN (-1937 3408);
FORCEPROP 2 LAST CDS_LIB mstr_standard
J 0
(-1875 3400);
PAINT ORANGE (-1875 3400);
DISPLAY INVISIBLE (-1875 3400);
FORCEPROP 1 LAST PATH I134
J 0
(-1877 3400);
DISPLAY 0.872340 (-1877 3400);
PAINT GREEN (-1877 3400);
DISPLAY INVISIBLE (-1877 3400);
FORCEPROP 1 LAST BODY_TYPE PLUMBING
J 0
(-1875 3450);
DISPLAY 1.446809 (-1875 3450);
PAINT GREEN (-1875 3450);
DISPLAY INVISIBLE (-1875 3450);
FORCEPROP 1 LAST HDL_TAP TRUE
J 0
(-1550 3275);
DISPLAY 1.446809 (-1550 3275);
PAINT GREEN (-1550 3275);
DISPLAY INVISIBLE (-1550 3275);
FORCEADD TAP..1
(-2025 3950);
FORCEPROP 3 LASTPIN (-2075 3950) SIG_NAME SATA6G_PCH_PCIE_UP_SATA_TXP<5>
J 0
(-2065 3960);
DISPLAY 0.659574 (-2065 3960);
PAINT MONO (-2065 3960);
DISPLAY INVISIBLE (-2065 3960);
FORCEPROP 1 LASTPIN (-2075 3950) BN 5
J 0
(-2087 3958);
DISPLAY 0.617021 (-2087 3958);
PAINT GREEN (-2087 3958);
FORCEPROP 1 LAST PATH I135
J 0
(-2027 3950);
DISPLAY 0.872340 (-2027 3950);
PAINT GREEN (-2027 3950);
DISPLAY INVISIBLE (-2027 3950);
FORCEPROP 2 LAST CDS_LIB mstr_standard
J 0
(-2025 3950);
PAINT ORANGE (-2025 3950);
DISPLAY INVISIBLE (-2025 3950);
FORCEPROP 1 LAST BODY_TYPE PLUMBING
J 0
(-2025 4000);
DISPLAY 1.446809 (-2025 4000);
PAINT GREEN (-2025 4000);
DISPLAY INVISIBLE (-2025 4000);
FORCEPROP 1 LAST HDL_TAP TRUE
J 0
(-1700 3825);
DISPLAY 1.446809 (-1700 3825);
PAINT GREEN (-1700 3825);
DISPLAY INVISIBLE (-1700 3825);
FORCEADD TAP..1
(-2025 3850);
FORCEPROP 3 LASTPIN (-2075 3850) SIG_NAME SATA6G_PCH_PCIE_UP_SATA_TXP<4>
J 0
(-2065 3860);
DISPLAY 0.659574 (-2065 3860);
PAINT MONO (-2065 3860);
DISPLAY INVISIBLE (-2065 3860);
FORCEPROP 1 LASTPIN (-2075 3850) BN 4
J 0
(-2087 3858);
DISPLAY 0.617021 (-2087 3858);
PAINT GREEN (-2087 3858);
FORCEPROP 2 LAST CDS_LIB mstr_standard
J 0
(-2025 3850);
PAINT ORANGE (-2025 3850);
DISPLAY INVISIBLE (-2025 3850);
FORCEPROP 1 LAST BODY_TYPE PLUMBING
J 0
(-2025 3900);
DISPLAY 1.446809 (-2025 3900);
PAINT GREEN (-2025 3900);
DISPLAY INVISIBLE (-2025 3900);
FORCEPROP 1 LAST PATH I136
J 0
(-2027 3850);
DISPLAY 0.872340 (-2027 3850);
PAINT GREEN (-2027 3850);
DISPLAY INVISIBLE (-2027 3850);
FORCEPROP 1 LAST HDL_TAP TRUE
J 0
(-1700 3725);
DISPLAY 1.446809 (-1700 3725);
PAINT GREEN (-1700 3725);
DISPLAY INVISIBLE (-1700 3725);
FORCEADD TAP..1
(-2025 3750);
FORCEPROP 3 LASTPIN (-2075 3750) SIG_NAME SATA6G_PCH_PCIE_UP_SATA_TXP<3>
J 0
(-2065 3760);
DISPLAY 0.659574 (-2065 3760);
PAINT MONO (-2065 3760);
DISPLAY INVISIBLE (-2065 3760);
FORCEPROP 1 LASTPIN (-2075 3750) BN 3
J 0
(-2087 3758);
DISPLAY 0.617021 (-2087 3758);
PAINT GREEN (-2087 3758);
FORCEPROP 2 LAST CDS_LIB mstr_standard
J 0
(-2025 3750);
PAINT ORANGE (-2025 3750);
DISPLAY INVISIBLE (-2025 3750);
FORCEPROP 1 LAST PATH I137
J 0
(-2027 3750);
DISPLAY 0.872340 (-2027 3750);
PAINT GREEN (-2027 3750);
DISPLAY INVISIBLE (-2027 3750);
FORCEPROP 1 LAST BODY_TYPE PLUMBING
J 0
(-2025 3800);
DISPLAY 1.446809 (-2025 3800);
PAINT GREEN (-2025 3800);
DISPLAY INVISIBLE (-2025 3800);
FORCEPROP 1 LAST HDL_TAP TRUE
J 0
(-1700 3625);
DISPLAY 1.446809 (-1700 3625);
PAINT GREEN (-1700 3625);
DISPLAY INVISIBLE (-1700 3625);
FORCEADD TAP..1
(-2025 3650);
FORCEPROP 3 LASTPIN (-2075 3650) SIG_NAME SATA6G_PCH_PCIE_UP_SATA_TXP<2>
J 0
(-2065 3660);
DISPLAY 0.659574 (-2065 3660);
PAINT MONO (-2065 3660);
DISPLAY INVISIBLE (-2065 3660);
FORCEPROP 1 LASTPIN (-2075 3650) BN 2
J 0
(-2087 3658);
DISPLAY 0.617021 (-2087 3658);
PAINT GREEN (-2087 3658);
FORCEPROP 1 LAST HDL_TAP TRUE
J 0
(-1700 3525);
DISPLAY 1.446809 (-1700 3525);
PAINT GREEN (-1700 3525);
DISPLAY INVISIBLE (-1700 3525);
FORCEPROP 2 LAST CDS_LIB mstr_standard
J 0
(-2025 3650);
PAINT ORANGE (-2025 3650);
DISPLAY INVISIBLE (-2025 3650);
FORCEPROP 1 LAST PATH I138
J 0
(-2027 3650);
DISPLAY 0.872340 (-2027 3650);
PAINT GREEN (-2027 3650);
DISPLAY INVISIBLE (-2027 3650);
FORCEPROP 1 LAST BODY_TYPE PLUMBING
J 0
(-2025 3700);
DISPLAY 1.446809 (-2025 3700);
PAINT GREEN (-2025 3700);
DISPLAY INVISIBLE (-2025 3700);
FORCEADD TAP..1
(-2025 3550);
FORCEPROP 3 LASTPIN (-2075 3550) SIG_NAME SATA6G_PCH_PCIE_UP_SATA_TXP<1>
J 0
(-2065 3560);
DISPLAY 0.659574 (-2065 3560);
PAINT MONO (-2065 3560);
DISPLAY INVISIBLE (-2065 3560);
FORCEPROP 1 LASTPIN (-2075 3550) BN 1
J 0
(-2087 3558);
DISPLAY 0.617021 (-2087 3558);
PAINT GREEN (-2087 3558);
FORCEPROP 1 LAST HDL_TAP TRUE
J 0
(-1700 3425);
DISPLAY 1.446809 (-1700 3425);
PAINT GREEN (-1700 3425);
DISPLAY INVISIBLE (-1700 3425);
FORCEPROP 1 LAST PATH I139
J 0
(-2027 3550);
DISPLAY 0.872340 (-2027 3550);
PAINT GREEN (-2027 3550);
DISPLAY INVISIBLE (-2027 3550);
FORCEPROP 2 LAST CDS_LIB mstr_standard
J 0
(-2025 3550);
PAINT ORANGE (-2025 3550);
DISPLAY INVISIBLE (-2025 3550);
FORCEPROP 1 LAST BODY_TYPE PLUMBING
J 0
(-2025 3600);
DISPLAY 1.446809 (-2025 3600);
PAINT GREEN (-2025 3600);
DISPLAY INVISIBLE (-2025 3600);
FORCEADD TAP..1
(-2025 3450);
FORCEPROP 3 LASTPIN (-2075 3450) SIG_NAME SATA6G_PCH_PCIE_UP_SATA_TXP<0>
J 0
(-2065 3460);
DISPLAY 0.659574 (-2065 3460);
PAINT MONO (-2065 3460);
DISPLAY INVISIBLE (-2065 3460);
FORCEPROP 1 LASTPIN (-2075 3450) BN 0
J 0
(-2087 3458);
DISPLAY 0.617021 (-2087 3458);
PAINT GREEN (-2087 3458);
FORCEPROP 2 LAST CDS_LIB mstr_standard
J 0
(-2025 3450);
PAINT ORANGE (-2025 3450);
DISPLAY INVISIBLE (-2025 3450);
FORCEPROP 1 LAST PATH I140
J 0
(-2027 3450);
DISPLAY 0.872340 (-2027 3450);
PAINT GREEN (-2027 3450);
DISPLAY INVISIBLE (-2027 3450);
FORCEPROP 1 LAST BODY_TYPE PLUMBING
J 0
(-2025 3500);
DISPLAY 1.446809 (-2025 3500);
PAINT GREEN (-2025 3500);
DISPLAY INVISIBLE (-2025 3500);
FORCEPROP 1 LAST HDL_TAP TRUE
J 0
(-1700 3325);
DISPLAY 1.446809 (-1700 3325);
PAINT GREEN (-1700 3325);
DISPLAY INVISIBLE (-1700 3325);
FORCEADD TAP..1
R 2
(-6400 3450);
FORCEPROP 3 LASTPIN (-6350 3450) SIG_NAME SATA6G_PCH_PCIE_UP_SATA_RXP<0>
J 0
(-6340 3460);
DISPLAY 0.659574 (-6340 3460);
PAINT MONO (-6340 3460);
DISPLAY INVISIBLE (-6340 3460);
FORCEPROP 1 LASTPIN (-6350 3450) BN 0
J 2
(-6338 3458);
DISPLAY 0.617021 (-6338 3458);
PAINT GREEN (-6338 3458);
FORCEPROP 1 LAST HDL_TAP TRUE
J 2
(-6725 3325);
DISPLAY 1.446809 (-6725 3325);
PAINT GREEN (-6725 3325);
DISPLAY INVISIBLE (-6725 3325);
FORCEPROP 1 LAST BODY_TYPE PLUMBING
J 2
(-6400 3500);
DISPLAY 1.446809 (-6400 3500);
PAINT GREEN (-6400 3500);
DISPLAY INVISIBLE (-6400 3500);
FORCEPROP 2 LAST CDS_LIB mstr_standard
J 2
(-6400 3450);
PAINT ORANGE (-6400 3450);
DISPLAY INVISIBLE (-6400 3450);
FORCEPROP 1 LAST PATH I141
J 2
(-6398 3450);
DISPLAY 0.872340 (-6398 3450);
PAINT GREEN (-6398 3450);
DISPLAY INVISIBLE (-6398 3450);
FORCEADD TAP..1
R 2
(-6250 3400);
FORCEPROP 3 LASTPIN (-6200 3400) SIG_NAME SATA6G_PCH_PCIE_UP_SATA_RXN<0>
J 0
(-6190 3410);
DISPLAY 0.659574 (-6190 3410);
PAINT MONO (-6190 3410);
DISPLAY INVISIBLE (-6190 3410);
FORCEPROP 1 LASTPIN (-6200 3400) BN 0
J 2
(-6188 3408);
DISPLAY 0.617021 (-6188 3408);
PAINT GREEN (-6188 3408);
FORCEPROP 1 LAST HDL_TAP TRUE
J 2
(-6575 3275);
DISPLAY 1.446809 (-6575 3275);
PAINT GREEN (-6575 3275);
DISPLAY INVISIBLE (-6575 3275);
FORCEPROP 2 LAST CDS_LIB mstr_standard
J 2
(-6250 3400);
PAINT ORANGE (-6250 3400);
DISPLAY INVISIBLE (-6250 3400);
FORCEPROP 1 LAST PATH I142
J 2
(-6248 3400);
DISPLAY 0.872340 (-6248 3400);
PAINT GREEN (-6248 3400);
DISPLAY INVISIBLE (-6248 3400);
FORCEPROP 1 LAST BODY_TYPE PLUMBING
J 2
(-6250 3450);
DISPLAY 1.446809 (-6250 3450);
PAINT GREEN (-6250 3450);
DISPLAY INVISIBLE (-6250 3450);
FORCEADD TAP..1
R 2
(-6250 3500);
FORCEPROP 3 LASTPIN (-6200 3500) SIG_NAME SATA6G_PCH_PCIE_UP_SATA_RXN<1>
J 0
(-6190 3510);
DISPLAY 0.659574 (-6190 3510);
PAINT MONO (-6190 3510);
DISPLAY INVISIBLE (-6190 3510);
FORCEPROP 1 LASTPIN (-6200 3500) BN 1
J 2
(-6188 3508);
DISPLAY 0.617021 (-6188 3508);
PAINT GREEN (-6188 3508);
FORCEPROP 1 LAST HDL_TAP TRUE
J 2
(-6575 3375);
DISPLAY 1.446809 (-6575 3375);
PAINT GREEN (-6575 3375);
DISPLAY INVISIBLE (-6575 3375);
FORCEPROP 1 LAST PATH I143
J 2
(-6248 3500);
DISPLAY 0.872340 (-6248 3500);
PAINT GREEN (-6248 3500);
DISPLAY INVISIBLE (-6248 3500);
FORCEPROP 2 LAST CDS_LIB mstr_standard
J 2
(-6250 3500);
PAINT ORANGE (-6250 3500);
DISPLAY INVISIBLE (-6250 3500);
FORCEPROP 1 LAST BODY_TYPE PLUMBING
J 2
(-6250 3550);
DISPLAY 1.446809 (-6250 3550);
PAINT GREEN (-6250 3550);
DISPLAY INVISIBLE (-6250 3550);
FORCEADD TAP..1
R 2
(-6400 3650);
FORCEPROP 3 LASTPIN (-6350 3650) SIG_NAME SATA6G_PCH_PCIE_UP_SATA_RXP<2>
J 0
(-6340 3660);
DISPLAY 0.659574 (-6340 3660);
PAINT MONO (-6340 3660);
DISPLAY INVISIBLE (-6340 3660);
FORCEPROP 1 LASTPIN (-6350 3650) BN 2
J 2
(-6338 3658);
DISPLAY 0.617021 (-6338 3658);
PAINT GREEN (-6338 3658);
FORCEPROP 1 LAST HDL_TAP TRUE
J 2
(-6725 3525);
DISPLAY 1.446809 (-6725 3525);
PAINT GREEN (-6725 3525);
DISPLAY INVISIBLE (-6725 3525);
FORCEPROP 1 LAST BODY_TYPE PLUMBING
J 2
(-6400 3700);
DISPLAY 1.446809 (-6400 3700);
PAINT GREEN (-6400 3700);
DISPLAY INVISIBLE (-6400 3700);
FORCEPROP 2 LAST CDS_LIB mstr_standard
J 2
(-6400 3650);
PAINT ORANGE (-6400 3650);
DISPLAY INVISIBLE (-6400 3650);
FORCEPROP 1 LAST PATH I144
J 2
(-6398 3650);
DISPLAY 0.872340 (-6398 3650);
PAINT GREEN (-6398 3650);
DISPLAY INVISIBLE (-6398 3650);
FORCEADD TAP..1
R 2
(-6400 3750);
FORCEPROP 3 LASTPIN (-6350 3750) SIG_NAME SATA6G_PCH_PCIE_UP_SATA_RXP<3>
J 0
(-6340 3760);
DISPLAY 0.659574 (-6340 3760);
PAINT MONO (-6340 3760);
DISPLAY INVISIBLE (-6340 3760);
FORCEPROP 1 LASTPIN (-6350 3750) BN 3
J 2
(-6338 3758);
DISPLAY 0.617021 (-6338 3758);
PAINT GREEN (-6338 3758);
FORCEPROP 1 LAST HDL_TAP TRUE
J 2
(-6725 3625);
DISPLAY 1.446809 (-6725 3625);
PAINT GREEN (-6725 3625);
DISPLAY INVISIBLE (-6725 3625);
FORCEPROP 1 LAST BODY_TYPE PLUMBING
J 2
(-6400 3800);
DISPLAY 1.446809 (-6400 3800);
PAINT GREEN (-6400 3800);
DISPLAY INVISIBLE (-6400 3800);
FORCEPROP 2 LAST CDS_LIB mstr_standard
J 2
(-6400 3750);
PAINT ORANGE (-6400 3750);
DISPLAY INVISIBLE (-6400 3750);
FORCEPROP 1 LAST PATH I145
J 2
(-6398 3750);
DISPLAY 0.872340 (-6398 3750);
PAINT GREEN (-6398 3750);
DISPLAY INVISIBLE (-6398 3750);
FORCEADD TAP..1
R 2
(-6400 3550);
FORCEPROP 3 LASTPIN (-6350 3550) SIG_NAME SATA6G_PCH_PCIE_UP_SATA_RXP<1>
J 0
(-6340 3560);
DISPLAY 0.659574 (-6340 3560);
PAINT MONO (-6340 3560);
DISPLAY INVISIBLE (-6340 3560);
FORCEPROP 1 LASTPIN (-6350 3550) BN 1
J 2
(-6338 3558);
DISPLAY 0.617021 (-6338 3558);
PAINT GREEN (-6338 3558);
FORCEPROP 1 LAST HDL_TAP TRUE
J 2
(-6725 3425);
DISPLAY 1.446809 (-6725 3425);
PAINT GREEN (-6725 3425);
DISPLAY INVISIBLE (-6725 3425);
FORCEPROP 1 LAST PATH I146
J 2
(-6398 3550);
DISPLAY 0.872340 (-6398 3550);
PAINT GREEN (-6398 3550);
DISPLAY INVISIBLE (-6398 3550);
FORCEPROP 2 LAST CDS_LIB mstr_standard
J 2
(-6400 3550);
PAINT ORANGE (-6400 3550);
DISPLAY INVISIBLE (-6400 3550);
FORCEPROP 1 LAST BODY_TYPE PLUMBING
J 2
(-6400 3600);
DISPLAY 1.446809 (-6400 3600);
PAINT GREEN (-6400 3600);
DISPLAY INVISIBLE (-6400 3600);
FORCEADD TAP..1
R 2
(-6250 3600);
FORCEPROP 3 LASTPIN (-6200 3600) SIG_NAME SATA6G_PCH_PCIE_UP_SATA_RXN<2>
J 0
(-6190 3610);
DISPLAY 0.659574 (-6190 3610);
PAINT MONO (-6190 3610);
DISPLAY INVISIBLE (-6190 3610);
FORCEPROP 1 LASTPIN (-6200 3600) BN 2
J 2
(-6188 3608);
DISPLAY 0.617021 (-6188 3608);
PAINT GREEN (-6188 3608);
FORCEPROP 1 LAST HDL_TAP TRUE
J 2
(-6575 3475);
DISPLAY 1.446809 (-6575 3475);
PAINT GREEN (-6575 3475);
DISPLAY INVISIBLE (-6575 3475);
FORCEPROP 1 LAST PATH I147
J 2
(-6248 3600);
DISPLAY 0.872340 (-6248 3600);
PAINT GREEN (-6248 3600);
DISPLAY INVISIBLE (-6248 3600);
FORCEPROP 1 LAST BODY_TYPE PLUMBING
J 2
(-6250 3650);
DISPLAY 1.446809 (-6250 3650);
PAINT GREEN (-6250 3650);
DISPLAY INVISIBLE (-6250 3650);
FORCEPROP 2 LAST CDS_LIB mstr_standard
J 2
(-6250 3600);
PAINT ORANGE (-6250 3600);
DISPLAY INVISIBLE (-6250 3600);
FORCEADD TAP..1
R 2
(-6250 3700);
FORCEPROP 3 LASTPIN (-6200 3700) SIG_NAME SATA6G_PCH_PCIE_UP_SATA_RXN<3>
J 0
(-6190 3710);
DISPLAY 0.659574 (-6190 3710);
PAINT MONO (-6190 3710);
DISPLAY INVISIBLE (-6190 3710);
FORCEPROP 1 LASTPIN (-6200 3700) BN 3
J 2
(-6188 3708);
DISPLAY 0.617021 (-6188 3708);
PAINT GREEN (-6188 3708);
FORCEPROP 1 LAST HDL_TAP TRUE
J 2
(-6575 3575);
DISPLAY 1.446809 (-6575 3575);
PAINT GREEN (-6575 3575);
DISPLAY INVISIBLE (-6575 3575);
FORCEPROP 2 LAST CDS_LIB mstr_standard
J 2
(-6250 3700);
PAINT ORANGE (-6250 3700);
DISPLAY INVISIBLE (-6250 3700);
FORCEPROP 1 LAST PATH I148
J 2
(-6248 3700);
DISPLAY 0.872340 (-6248 3700);
PAINT GREEN (-6248 3700);
DISPLAY INVISIBLE (-6248 3700);
FORCEPROP 1 LAST BODY_TYPE PLUMBING
J 2
(-6250 3750);
DISPLAY 1.446809 (-6250 3750);
PAINT GREEN (-6250 3750);
DISPLAY INVISIBLE (-6250 3750);
FORCEADD TAP..1
R 2
(-6400 3850);
FORCEPROP 3 LASTPIN (-6350 3850) SIG_NAME SATA6G_PCH_PCIE_UP_SATA_RXP<4>
J 0
(-6340 3860);
DISPLAY 0.659574 (-6340 3860);
PAINT MONO (-6340 3860);
DISPLAY INVISIBLE (-6340 3860);
FORCEPROP 1 LASTPIN (-6350 3850) BN 4
J 2
(-6338 3858);
DISPLAY 0.617021 (-6338 3858);
PAINT GREEN (-6338 3858);
FORCEPROP 1 LAST HDL_TAP TRUE
J 2
(-6725 3725);
DISPLAY 1.446809 (-6725 3725);
PAINT GREEN (-6725 3725);
DISPLAY INVISIBLE (-6725 3725);
FORCEPROP 1 LAST BODY_TYPE PLUMBING
J 2
(-6400 3900);
DISPLAY 1.446809 (-6400 3900);
PAINT GREEN (-6400 3900);
DISPLAY INVISIBLE (-6400 3900);
FORCEPROP 2 LAST CDS_LIB mstr_standard
J 2
(-6400 3850);
PAINT ORANGE (-6400 3850);
DISPLAY INVISIBLE (-6400 3850);
FORCEPROP 1 LAST PATH I149
J 2
(-6398 3850);
DISPLAY 0.872340 (-6398 3850);
PAINT GREEN (-6398 3850);
DISPLAY INVISIBLE (-6398 3850);
FORCEADD TAP..1
R 2
(-6400 3950);
FORCEPROP 3 LASTPIN (-6350 3950) SIG_NAME SATA6G_PCH_PCIE_UP_SATA_RXP<5>
J 0
(-6340 3960);
DISPLAY 0.659574 (-6340 3960);
PAINT MONO (-6340 3960);
DISPLAY INVISIBLE (-6340 3960);
FORCEPROP 1 LASTPIN (-6350 3950) BN 5
J 2
(-6338 3958);
DISPLAY 0.617021 (-6338 3958);
PAINT GREEN (-6338 3958);
FORCEPROP 1 LAST HDL_TAP TRUE
J 2
(-6725 3825);
DISPLAY 1.446809 (-6725 3825);
PAINT GREEN (-6725 3825);
DISPLAY INVISIBLE (-6725 3825);
FORCEPROP 1 LAST BODY_TYPE PLUMBING
J 2
(-6400 4000);
DISPLAY 1.446809 (-6400 4000);
PAINT GREEN (-6400 4000);
DISPLAY INVISIBLE (-6400 4000);
FORCEPROP 2 LAST CDS_LIB mstr_standard
J 2
(-6400 3950);
PAINT ORANGE (-6400 3950);
DISPLAY INVISIBLE (-6400 3950);
FORCEPROP 1 LAST PATH I150
J 2
(-6398 3950);
DISPLAY 0.872340 (-6398 3950);
PAINT GREEN (-6398 3950);
DISPLAY INVISIBLE (-6398 3950);
FORCEADD TAP..1
R 2
(-6250 4000);
FORCEPROP 3 LASTPIN (-6200 4000) SIG_NAME SATA6G_PCH_PCIE_UP_SATA_RXN<6>
J 0
(-6190 4010);
DISPLAY 0.659574 (-6190 4010);
PAINT MONO (-6190 4010);
DISPLAY INVISIBLE (-6190 4010);
FORCEPROP 1 LASTPIN (-6200 4000) BN 6
J 2
(-6188 4008);
DISPLAY 0.617021 (-6188 4008);
PAINT GREEN (-6188 4008);
FORCEPROP 1 LAST HDL_TAP TRUE
J 2
(-6575 3875);
DISPLAY 1.446809 (-6575 3875);
PAINT GREEN (-6575 3875);
DISPLAY INVISIBLE (-6575 3875);
FORCEPROP 2 LAST CDS_LIB mstr_standard
J 2
(-6250 4000);
PAINT ORANGE (-6250 4000);
DISPLAY INVISIBLE (-6250 4000);
FORCEPROP 1 LAST PATH I151
J 2
(-6248 4000);
DISPLAY 0.872340 (-6248 4000);
PAINT GREEN (-6248 4000);
DISPLAY INVISIBLE (-6248 4000);
FORCEPROP 1 LAST BODY_TYPE PLUMBING
J 2
(-6250 4050);
DISPLAY 1.446809 (-6250 4050);
PAINT GREEN (-6250 4050);
DISPLAY INVISIBLE (-6250 4050);
FORCEADD TAP..1
R 2
(-6250 3900);
FORCEPROP 3 LASTPIN (-6200 3900) SIG_NAME SATA6G_PCH_PCIE_UP_SATA_RXN<5>
J 0
(-6190 3910);
DISPLAY 0.659574 (-6190 3910);
PAINT MONO (-6190 3910);
DISPLAY INVISIBLE (-6190 3910);
FORCEPROP 1 LASTPIN (-6200 3900) BN 5
J 2
(-6188 3908);
DISPLAY 0.617021 (-6188 3908);
PAINT GREEN (-6188 3908);
FORCEPROP 1 LAST HDL_TAP TRUE
J 2
(-6575 3775);
DISPLAY 1.446809 (-6575 3775);
PAINT GREEN (-6575 3775);
DISPLAY INVISIBLE (-6575 3775);
FORCEPROP 2 LAST CDS_LIB mstr_standard
J 2
(-6250 3900);
PAINT ORANGE (-6250 3900);
DISPLAY INVISIBLE (-6250 3900);
FORCEPROP 1 LAST PATH I152
J 2
(-6248 3900);
DISPLAY 0.872340 (-6248 3900);
PAINT GREEN (-6248 3900);
DISPLAY INVISIBLE (-6248 3900);
FORCEPROP 1 LAST BODY_TYPE PLUMBING
J 2
(-6250 3950);
DISPLAY 1.446809 (-6250 3950);
PAINT GREEN (-6250 3950);
DISPLAY INVISIBLE (-6250 3950);
FORCEADD TAP..1
R 2
(-6250 3800);
FORCEPROP 3 LASTPIN (-6200 3800) SIG_NAME SATA6G_PCH_PCIE_UP_SATA_RXN<4>
J 0
(-6190 3810);
DISPLAY 0.659574 (-6190 3810);
PAINT MONO (-6190 3810);
DISPLAY INVISIBLE (-6190 3810);
FORCEPROP 1 LASTPIN (-6200 3800) BN 4
J 2
(-6188 3808);
DISPLAY 0.617021 (-6188 3808);
PAINT GREEN (-6188 3808);
FORCEPROP 1 LAST HDL_TAP TRUE
J 2
(-6575 3675);
DISPLAY 1.446809 (-6575 3675);
PAINT GREEN (-6575 3675);
DISPLAY INVISIBLE (-6575 3675);
FORCEPROP 1 LAST PATH I153
J 2
(-6248 3800);
DISPLAY 0.872340 (-6248 3800);
PAINT GREEN (-6248 3800);
DISPLAY INVISIBLE (-6248 3800);
FORCEPROP 2 LAST CDS_LIB mstr_standard
J 2
(-6250 3800);
PAINT ORANGE (-6250 3800);
DISPLAY INVISIBLE (-6250 3800);
FORCEPROP 1 LAST BODY_TYPE PLUMBING
J 2
(-6250 3850);
DISPLAY 1.446809 (-6250 3850);
PAINT GREEN (-6250 3850);
DISPLAY INVISIBLE (-6250 3850);
FORCEADD TAP..1
R 2
(-6400 4150);
FORCEPROP 3 LASTPIN (-6350 4150) SIG_NAME SATA6G_PCH_PCIE_UP_SATA_RXP<7>
J 0
(-6340 4160);
DISPLAY 0.659574 (-6340 4160);
PAINT MONO (-6340 4160);
DISPLAY INVISIBLE (-6340 4160);
FORCEPROP 1 LASTPIN (-6350 4150) BN 7
J 2
(-6338 4158);
DISPLAY 0.617021 (-6338 4158);
PAINT GREEN (-6338 4158);
FORCEPROP 1 LAST HDL_TAP TRUE
J 2
(-6725 4025);
DISPLAY 1.446809 (-6725 4025);
PAINT GREEN (-6725 4025);
DISPLAY INVISIBLE (-6725 4025);
FORCEPROP 1 LAST BODY_TYPE PLUMBING
J 2
(-6400 4200);
DISPLAY 1.446809 (-6400 4200);
PAINT GREEN (-6400 4200);
DISPLAY INVISIBLE (-6400 4200);
FORCEPROP 2 LAST CDS_LIB mstr_standard
J 2
(-6400 4150);
PAINT ORANGE (-6400 4150);
DISPLAY INVISIBLE (-6400 4150);
FORCEPROP 1 LAST PATH I154
J 2
(-6398 4150);
DISPLAY 0.872340 (-6398 4150);
PAINT GREEN (-6398 4150);
DISPLAY INVISIBLE (-6398 4150);
FORCEADD TAP..1
R 2
(-6400 4050);
FORCEPROP 3 LASTPIN (-6350 4050) SIG_NAME SATA6G_PCH_PCIE_UP_SATA_RXP<6>
J 0
(-6340 4060);
DISPLAY 0.659574 (-6340 4060);
PAINT MONO (-6340 4060);
DISPLAY INVISIBLE (-6340 4060);
FORCEPROP 1 LASTPIN (-6350 4050) BN 6
J 2
(-6338 4058);
DISPLAY 0.617021 (-6338 4058);
PAINT GREEN (-6338 4058);
FORCEPROP 1 LAST HDL_TAP TRUE
J 2
(-6725 3925);
DISPLAY 1.446809 (-6725 3925);
PAINT GREEN (-6725 3925);
DISPLAY INVISIBLE (-6725 3925);
FORCEPROP 2 LAST CDS_LIB mstr_standard
J 2
(-6400 4050);
PAINT ORANGE (-6400 4050);
DISPLAY INVISIBLE (-6400 4050);
FORCEPROP 1 LAST PATH I155
J 2
(-6398 4050);
DISPLAY 0.872340 (-6398 4050);
PAINT GREEN (-6398 4050);
DISPLAY INVISIBLE (-6398 4050);
FORCEPROP 1 LAST BODY_TYPE PLUMBING
J 2
(-6400 4100);
DISPLAY 1.446809 (-6400 4100);
PAINT GREEN (-6400 4100);
DISPLAY INVISIBLE (-6400 4100);
FORCEADD TAP..1
R 2
(-6250 4100);
FORCEPROP 3 LASTPIN (-6200 4100) SIG_NAME SATA6G_PCH_PCIE_UP_SATA_RXN<7>
J 0
(-6190 4110);
DISPLAY 0.659574 (-6190 4110);
PAINT MONO (-6190 4110);
DISPLAY INVISIBLE (-6190 4110);
FORCEPROP 1 LASTPIN (-6200 4100) BN 7
J 2
(-6188 4108);
DISPLAY 0.617021 (-6188 4108);
PAINT GREEN (-6188 4108);
FORCEPROP 1 LAST HDL_TAP TRUE
J 2
(-6575 3975);
DISPLAY 1.446809 (-6575 3975);
PAINT GREEN (-6575 3975);
DISPLAY INVISIBLE (-6575 3975);
FORCEPROP 1 LAST PATH I156
J 2
(-6248 4100);
DISPLAY 0.872340 (-6248 4100);
PAINT GREEN (-6248 4100);
DISPLAY INVISIBLE (-6248 4100);
FORCEPROP 1 LAST BODY_TYPE PLUMBING
J 2
(-6250 4150);
DISPLAY 1.446809 (-6250 4150);
PAINT GREEN (-6250 4150);
DISPLAY INVISIBLE (-6250 4150);
FORCEPROP 2 LAST CDS_LIB mstr_standard
J 2
(-6250 4100);
PAINT ORANGE (-6250 4100);
DISPLAY INVISIBLE (-6250 4100);
FORCEADD RES..2
R 2
(-7125 2150);
FORCEPROP 1 LAST PART_NUMBER G21796-017
J 2
(-7165 2025);
DISPLAY 0.617021 (-7165 2025);
PAINT BLUE (-7165 2025);
FORCEPROP 1 LAST VALUE 100.0
J 2
(-7170 2225);
DISPLAY 0.617021 (-7170 2225);
PAINT SKYBLUE (-7170 2225);
FORCEPROP 1 LAST TOLERANCE 1%
J 2
(-7170 2175);
DISPLAY 0.617021 (-7170 2175);
PAINT SKYBLUE (-7170 2175);
FORCEPROP 1 LAST MATERIAL CHIP
J 2
(-7165 2075);
DISPLAY 0.617021 (-7165 2075);
PAINT SKYBLUE (-7165 2075);
FORCEPROP 1 LASTPIN (-7125 2050) $PN 2
J 2
(-7130 2060);
DISPLAY 0.617021 (-7130 2060);
PAINT ORANGE (-7130 2060);
FORCEPROP 1 LASTPIN (-7125 2250) $PN 1
J 2
(-7130 2212);
DISPLAY 0.617021 (-7130 2212);
PAINT ORANGE (-7130 2212);
FORCEPROP 1 LAST LOCATION R3M12
J 2
(-7170 2275);
DISPLAY 0.617021 (-7170 2275);
PAINT AQUA (-7170 2275);
FORCEPROP 1 LAST WATTAGE 1/16W
J 2
(-7165 2125);
DISPLAY 0.617021 (-7165 2125);
PAINT SKYBLUE (-7165 2125);
FORCEPROP 1 LAST PACK_TYPE 0402
J 2
(-7165 1975);
DISPLAY 0.617021 (-7165 1975);
PAINT SKYBLUE (-7165 1975);
FORCEPROP 1 LAST PATH I181
J 2
(-7175 2325);
DISPLAY 0.978723 (-7175 2325);
PAINT WHITE (-7175 2325);
DISPLAY INVISIBLE (-7175 2325);
FORCEPROP 2 LAST SEC_TYPE 0402
J 0
(-7175 2375);
DISPLAY 1.021277 (-7175 2375);
PAINT ORANGE (-7175 2375);
DISPLAY INVISIBLE (-7175 2375);
FORCEPROP 0 LAST ROOM SB
J 2
(-7175 2375);
DISPLAY 1.021277 (-7175 2375);
PAINT ORANGE (-7175 2375);
DISPLAY INVISIBLE (-7175 2375);
FORCEPROP 2 LAST NO_XNET_CONNECTION 1
J 0
(-7175 2375);
PAINT MONO (-7175 2375);
DISPLAY INVISIBLE (-7175 2375);
FORCEPROP 2 LAST CDS_LOCATION R3M12
J 2
(-7170 2275);
DISPLAY 0.617021 (-7170 2275);
PAINT AQUA (-7170 2275);
DISPLAY INVISIBLE (-7170 2275);
FORCEPROP 2 LAST SEC 1
J 0
(-7175 2375);
DISPLAY 0.680851 (-7175 2375);
PAINT MONO (-7175 2375);
DISPLAY INVISIBLE (-7175 2375);
FORCEPROP 2 LAST CDS_LIB mstr_discrete
J 0
(-7125 2150);
PAINT ORANGE (-7125 2150);
DISPLAY INVISIBLE (-7125 2150);
FORCEADD CAP_A..2
(-1725 2650);
FORCEPROP 1 LAST PACK_TYPE 0402V
J 1
(-2025 2550);
DISPLAY 0.617021 (-2025 2550);
PAINT SKYBLUE (-2025 2550);
FORCEPROP 1 LAST VALUE 0.1UF
J 2
(-1725 2550);
DISPLAY 0.617021 (-1725 2550);
PAINT SKYBLUE (-1725 2550);
FORCEPROP 1 LAST TOLERANCE 10%
J 2
(-1875 2550);
DISPLAY 0.617021 (-1875 2550);
PAINT SKYBLUE (-1875 2550);
FORCEPROP 1 LAST VOLTAGE 16V
J 0
(-1725 2550);
DISPLAY 0.617021 (-1725 2550);
PAINT SKYBLUE (-1725 2550);
FORCEPROP 1 LASTPIN (-1825 2650) $PN 1
J 0
(-1835 2665);
DISPLAY 0.617021 (-1835 2665);
PAINT ORANGE (-1835 2665);
FORCEPROP 1 LAST PART_NUMBER A36096-030
J 1
(-1725 2700);
DISPLAY 0.617021 (-1725 2700);
PAINT BLUE (-1725 2700);
FORCEPROP 1 LASTPIN (-1625 2650) $PN 2
J 0
(-1640 2665);
DISPLAY 0.617021 (-1640 2665);
PAINT ORANGE (-1640 2665);
FORCEPROP 1 LAST MATERIAL EMPTY
J 0
(-1625 2550);
DISPLAY 0.617021 (-1625 2550);
PAINT RED (-1625 2550);
FORCEPROP 1 LAST LOCATION C2M4
J 1
(-1550 2650);
DISPLAY 0.617021 (-1550 2650);
PAINT AQUA (-1550 2650);
FORCEPROP 2 LAST CDS_LOCATION C2M4
J 1
(-1800 2675);
DISPLAY 0.617021 (-1800 2675);
PAINT AQUA (-1800 2675);
DISPLAY INVISIBLE (-1800 2675);
FORCEPROP 2 LAST CDS_LIB dev_discrete
J 0
(-1725 2650);
PAINT ORANGE (-1725 2650);
DISPLAY INVISIBLE (-1725 2650);
FORCEPROP 0 LAST ROOM SB
J 0
(-1550 2775);
DISPLAY 1.021277 (-1550 2775);
PAINT ORANGE (-1550 2775);
DISPLAY INVISIBLE (-1550 2775);
FORCEPROP 1 LAST PATH I182
J 0
(-1725 2850);
DISPLAY 0.978723 (-1725 2850);
PAINT WHITE (-1725 2850);
DISPLAY INVISIBLE (-1725 2850);
FORCEPROP 2 LAST SEC_TYPE 0402V
J 0
(-1725 2900);
DISPLAY 1.021277 (-1725 2900);
PAINT ORANGE (-1725 2900);
DISPLAY INVISIBLE (-1725 2900);
FORCEPROP 2 LAST SEC 1
J 0
(-1725 2900);
DISPLAY 0.680851 (-1725 2900);
PAINT MONO (-1725 2900);
DISPLAY INVISIBLE (-1725 2900);
FORCEADD CAP_A..2
(-1325 2600);
FORCEPROP 1 LAST PACK_TYPE 0402V
J 1
(-1375 2450);
DISPLAY 0.617021 (-1375 2450);
PAINT SKYBLUE (-1375 2450);
FORCEPROP 1 LAST MATERIAL EMPTY
J 0
(-1325 2450);
DISPLAY 0.617021 (-1325 2450);
PAINT RED (-1325 2450);
FORCEPROP 1 LAST TOLERANCE 10%
J 2
(-1400 2550);
DISPLAY 0.617021 (-1400 2550);
PAINT SKYBLUE (-1400 2550);
FORCEPROP 1 LAST VOLTAGE 16V
J 0
(-1200 2550);
DISPLAY 0.617021 (-1200 2550);
PAINT SKYBLUE (-1200 2550);
FORCEPROP 1 LASTPIN (-1425 2600) $PN 1
J 0
(-1435 2615);
DISPLAY 0.617021 (-1435 2615);
PAINT ORANGE (-1435 2615);
FORCEPROP 1 LAST PART_NUMBER A36096-030
J 1
(-1325 2650);
DISPLAY 0.617021 (-1325 2650);
PAINT BLUE (-1325 2650);
FORCEPROP 1 LASTPIN (-1225 2600) $PN 2
J 0
(-1240 2615);
DISPLAY 0.617021 (-1240 2615);
PAINT ORANGE (-1240 2615);
FORCEPROP 1 LAST LOCATION C2M3
J 1
(-1100 2600);
DISPLAY 0.617021 (-1100 2600);
PAINT AQUA (-1100 2600);
FORCEPROP 1 LAST VALUE 0.1UF
J 2
(-950 2550);
DISPLAY 0.617021 (-950 2550);
PAINT SKYBLUE (-950 2550);
FORCEPROP 2 LAST CDS_LOCATION C2M3
J 1
(-1300 2500);
DISPLAY 0.617021 (-1300 2500);
PAINT AQUA (-1300 2500);
DISPLAY INVISIBLE (-1300 2500);
FORCEPROP 2 LAST CDS_LIB dev_discrete
J 0
(-1325 2600);
PAINT ORANGE (-1325 2600);
DISPLAY INVISIBLE (-1325 2600);
FORCEPROP 1 LAST PATH I183
J 0
(-1325 2800);
DISPLAY 0.978723 (-1325 2800);
PAINT WHITE (-1325 2800);
DISPLAY INVISIBLE (-1325 2800);
FORCEPROP 2 LAST SEC_TYPE 0402V
J 0
(-1325 2850);
DISPLAY 1.021277 (-1325 2850);
PAINT ORANGE (-1325 2850);
DISPLAY INVISIBLE (-1325 2850);
FORCEPROP 2 LAST SEC 1
J 0
(-1325 2850);
DISPLAY 0.680851 (-1325 2850);
PAINT MONO (-1325 2850);
DISPLAY INVISIBLE (-1325 2850);
FORCEPROP 0 LAST ROOM SB
J 0
(-1150 2725);
DISPLAY 1.021277 (-1150 2725);
PAINT ORANGE (-1150 2725);
DISPLAY INVISIBLE (-1150 2725);
FORCEADD TAP..6
(-6800 3300);
FORCEPROP 3 LASTPIN (-6750 3300) SIG_NAME SATA6G_RX_DN<3>
J 0
(-6740 3310);
DISPLAY 0.659574 (-6740 3310);
PAINT MONO (-6740 3310);
DISPLAY INVISIBLE (-6740 3310);
FORCEPROP 1 LASTPIN (-6750 3300) BN 3
J 0
(-6802 3308);
DISPLAY 0.617021 (-6802 3308);
PAINT GREEN (-6802 3308);
FORCEPROP 1 LAST BODY_TYPE PLUMBING
J 0
(-6800 3250);
DISPLAY 0.872340 (-6800 3250);
PAINT GREEN (-6800 3250);
DISPLAY INVISIBLE (-6800 3250);
FORCEPROP 1 LAST PATH I186
J 0
(-6802 3300);
DISPLAY 0.872340 (-6802 3300);
PAINT GREEN (-6802 3300);
DISPLAY INVISIBLE (-6802 3300);
FORCEPROP 2 LAST CDS_LIB mstr_standard
J 0
(-6800 3300);
PAINT ORANGE (-6800 3300);
DISPLAY INVISIBLE (-6800 3300);
FORCEPROP 1 LAST HDL_TAP TRUE
J 0
(-6475 3175);
DISPLAY 0.872340 (-6475 3175);
PAINT ORANGE (-6475 3175);
DISPLAY INVISIBLE (-6475 3175);
FORCEADD TAP..6
(-6800 3200);
FORCEPROP 3 LASTPIN (-6750 3200) SIG_NAME SATA6G_RX_DN<2>
J 0
(-6740 3210);
DISPLAY 0.659574 (-6740 3210);
PAINT MONO (-6740 3210);
DISPLAY INVISIBLE (-6740 3210);
FORCEPROP 1 LASTPIN (-6750 3200) BN 2
J 0
(-6802 3208);
DISPLAY 0.617021 (-6802 3208);
PAINT GREEN (-6802 3208);
FORCEPROP 1 LAST BODY_TYPE PLUMBING
J 0
(-6800 3150);
DISPLAY 0.872340 (-6800 3150);
PAINT GREEN (-6800 3150);
DISPLAY INVISIBLE (-6800 3150);
FORCEPROP 2 LAST CDS_LIB mstr_standard
J 0
(-6800 3200);
PAINT ORANGE (-6800 3200);
DISPLAY INVISIBLE (-6800 3200);
FORCEPROP 1 LAST PATH I187
J 0
(-6802 3200);
DISPLAY 0.872340 (-6802 3200);
PAINT GREEN (-6802 3200);
DISPLAY INVISIBLE (-6802 3200);
FORCEPROP 1 LAST HDL_TAP TRUE
J 0
(-6475 3075);
DISPLAY 0.872340 (-6475 3075);
PAINT ORANGE (-6475 3075);
DISPLAY INVISIBLE (-6475 3075);
FORCEADD TAP..6
(-6800 3100);
FORCEPROP 3 LASTPIN (-6750 3100) SIG_NAME SATA6G_RX_DN<1>
J 0
(-6740 3110);
DISPLAY 0.659574 (-6740 3110);
PAINT MONO (-6740 3110);
DISPLAY INVISIBLE (-6740 3110);
FORCEPROP 1 LASTPIN (-6750 3100) BN 1
J 0
(-6802 3108);
DISPLAY 0.617021 (-6802 3108);
PAINT GREEN (-6802 3108);
FORCEPROP 1 LAST HDL_TAP TRUE
J 0
(-6475 2975);
DISPLAY 0.872340 (-6475 2975);
PAINT ORANGE (-6475 2975);
DISPLAY INVISIBLE (-6475 2975);
FORCEPROP 1 LAST BODY_TYPE PLUMBING
J 0
(-6800 3050);
DISPLAY 0.872340 (-6800 3050);
PAINT GREEN (-6800 3050);
DISPLAY INVISIBLE (-6800 3050);
FORCEPROP 2 LAST CDS_LIB mstr_standard
J 0
(-6800 3100);
PAINT ORANGE (-6800 3100);
DISPLAY INVISIBLE (-6800 3100);
FORCEPROP 1 LAST PATH I188
J 0
(-6802 3100);
DISPLAY 0.872340 (-6802 3100);
PAINT GREEN (-6802 3100);
DISPLAY INVISIBLE (-6802 3100);
FORCEADD TAP..6
(-6800 3000);
FORCEPROP 3 LASTPIN (-6750 3000) SIG_NAME SATA6G_RX_DN<0>
J 0
(-6740 3010);
DISPLAY 0.659574 (-6740 3010);
PAINT MONO (-6740 3010);
DISPLAY INVISIBLE (-6740 3010);
FORCEPROP 1 LASTPIN (-6750 3000) BN 0
J 0
(-6802 3008);
DISPLAY 0.617021 (-6802 3008);
PAINT GREEN (-6802 3008);
FORCEPROP 2 LAST CDS_LIB mstr_standard
J 0
(-6800 3000);
PAINT ORANGE (-6800 3000);
DISPLAY INVISIBLE (-6800 3000);
FORCEPROP 1 LAST BODY_TYPE PLUMBING
J 0
(-6800 2950);
DISPLAY 0.872340 (-6800 2950);
PAINT GREEN (-6800 2950);
DISPLAY INVISIBLE (-6800 2950);
FORCEPROP 1 LAST PATH I189
J 0
(-6802 3000);
DISPLAY 0.872340 (-6802 3000);
PAINT GREEN (-6802 3000);
DISPLAY INVISIBLE (-6802 3000);
FORCEPROP 1 LAST HDL_TAP TRUE
J 0
(-6475 2875);
DISPLAY 0.872340 (-6475 2875);
PAINT ORANGE (-6475 2875);
DISPLAY INVISIBLE (-6475 2875);
FORCEADD TAP..6
(-6650 3350);
FORCEPROP 3 LASTPIN (-6600 3350) SIG_NAME SATA6G_RX_DP<3>
J 0
(-6590 3360);
DISPLAY 0.659574 (-6590 3360);
PAINT MONO (-6590 3360);
DISPLAY INVISIBLE (-6590 3360);
FORCEPROP 1 LASTPIN (-6600 3350) BN 3
J 0
(-6652 3358);
DISPLAY 0.617021 (-6652 3358);
PAINT GREEN (-6652 3358);
FORCEPROP 1 LAST BODY_TYPE PLUMBING
J 0
(-6650 3300);
DISPLAY 0.872340 (-6650 3300);
PAINT GREEN (-6650 3300);
DISPLAY INVISIBLE (-6650 3300);
FORCEPROP 1 LAST PATH I190
J 0
(-6652 3350);
DISPLAY 0.872340 (-6652 3350);
PAINT GREEN (-6652 3350);
DISPLAY INVISIBLE (-6652 3350);
FORCEPROP 2 LAST CDS_LIB mstr_standard
J 0
(-6650 3350);
PAINT ORANGE (-6650 3350);
DISPLAY INVISIBLE (-6650 3350);
FORCEPROP 1 LAST HDL_TAP TRUE
J 0
(-6325 3225);
DISPLAY 0.872340 (-6325 3225);
PAINT ORANGE (-6325 3225);
DISPLAY INVISIBLE (-6325 3225);
FORCEADD TAP..6
(-6650 3250);
FORCEPROP 3 LASTPIN (-6600 3250) SIG_NAME SATA6G_RX_DP<2>
J 0
(-6590 3260);
DISPLAY 0.659574 (-6590 3260);
PAINT MONO (-6590 3260);
DISPLAY INVISIBLE (-6590 3260);
FORCEPROP 1 LASTPIN (-6600 3250) BN 2
J 0
(-6652 3258);
DISPLAY 0.617021 (-6652 3258);
PAINT GREEN (-6652 3258);
FORCEPROP 1 LAST BODY_TYPE PLUMBING
J 0
(-6650 3200);
DISPLAY 0.872340 (-6650 3200);
PAINT GREEN (-6650 3200);
DISPLAY INVISIBLE (-6650 3200);
FORCEPROP 1 LAST PATH I191
J 0
(-6652 3250);
DISPLAY 0.872340 (-6652 3250);
PAINT GREEN (-6652 3250);
DISPLAY INVISIBLE (-6652 3250);
FORCEPROP 2 LAST CDS_LIB mstr_standard
J 0
(-6650 3250);
PAINT ORANGE (-6650 3250);
DISPLAY INVISIBLE (-6650 3250);
FORCEPROP 1 LAST HDL_TAP TRUE
J 0
(-6325 3125);
DISPLAY 0.872340 (-6325 3125);
PAINT ORANGE (-6325 3125);
DISPLAY INVISIBLE (-6325 3125);
FORCEADD TAP..6
(-6650 3150);
FORCEPROP 3 LASTPIN (-6600 3150) SIG_NAME SATA6G_RX_DP<1>
J 0
(-6590 3160);
DISPLAY 0.659574 (-6590 3160);
PAINT MONO (-6590 3160);
DISPLAY INVISIBLE (-6590 3160);
FORCEPROP 1 LASTPIN (-6600 3150) BN 1
J 0
(-6652 3158);
DISPLAY 0.617021 (-6652 3158);
PAINT GREEN (-6652 3158);
FORCEPROP 1 LAST HDL_TAP TRUE
J 0
(-6325 3025);
DISPLAY 0.872340 (-6325 3025);
PAINT ORANGE (-6325 3025);
DISPLAY INVISIBLE (-6325 3025);
FORCEPROP 2 LAST CDS_LIB mstr_standard
J 0
(-6650 3150);
PAINT ORANGE (-6650 3150);
DISPLAY INVISIBLE (-6650 3150);
FORCEPROP 1 LAST BODY_TYPE PLUMBING
J 0
(-6650 3100);
DISPLAY 0.872340 (-6650 3100);
PAINT GREEN (-6650 3100);
DISPLAY INVISIBLE (-6650 3100);
FORCEPROP 1 LAST PATH I192
J 0
(-6652 3150);
DISPLAY 0.872340 (-6652 3150);
PAINT GREEN (-6652 3150);
DISPLAY INVISIBLE (-6652 3150);
FORCEADD TAP..6
(-6650 3050);
FORCEPROP 3 LASTPIN (-6600 3050) SIG_NAME SATA6G_RX_DP<0>
J 0
(-6590 3060);
DISPLAY 0.659574 (-6590 3060);
PAINT MONO (-6590 3060);
DISPLAY INVISIBLE (-6590 3060);
FORCEPROP 1 LASTPIN (-6600 3050) BN 0
J 0
(-6652 3058);
DISPLAY 0.617021 (-6652 3058);
PAINT GREEN (-6652 3058);
FORCEPROP 1 LAST HDL_TAP TRUE
J 0
(-6325 2925);
DISPLAY 0.872340 (-6325 2925);
PAINT ORANGE (-6325 2925);
DISPLAY INVISIBLE (-6325 2925);
FORCEPROP 1 LAST BODY_TYPE PLUMBING
J 0
(-6650 3000);
DISPLAY 0.872340 (-6650 3000);
PAINT GREEN (-6650 3000);
DISPLAY INVISIBLE (-6650 3000);
FORCEPROP 1 LAST PATH I193
J 0
(-6652 3050);
DISPLAY 0.872340 (-6652 3050);
PAINT GREEN (-6652 3050);
DISPLAY INVISIBLE (-6652 3050);
FORCEPROP 2 LAST CDS_LIB mstr_standard
J 0
(-6650 3050);
PAINT ORANGE (-6650 3050);
DISPLAY INVISIBLE (-6650 3050);
FORCEADD TAP..1
(-1550 3350);
FORCEPROP 3 LASTPIN (-1600 3350) SIG_NAME SATA6G_TX_DP<3>
J 0
(-1590 3360);
DISPLAY 0.659574 (-1590 3360);
PAINT MONO (-1590 3360);
DISPLAY INVISIBLE (-1590 3360);
FORCEPROP 1 LASTPIN (-1600 3350) BN 3
J 0
(-1612 3358);
DISPLAY 0.617021 (-1612 3358);
PAINT GREEN (-1612 3358);
FORCEPROP 1 LAST PATH I196
J 0
(-1552 3350);
DISPLAY 0.872340 (-1552 3350);
PAINT GREEN (-1552 3350);
DISPLAY INVISIBLE (-1552 3350);
FORCEPROP 1 LAST BODY_TYPE PLUMBING
J 0
(-1550 3400);
DISPLAY 0.872340 (-1550 3400);
PAINT GREEN (-1550 3400);
DISPLAY INVISIBLE (-1550 3400);
FORCEPROP 2 LAST CDS_LIB mstr_standard
J 0
(-1550 3350);
PAINT ORANGE (-1550 3350);
DISPLAY INVISIBLE (-1550 3350);
FORCEPROP 1 LAST HDL_TAP TRUE
J 0
(-1225 3225);
DISPLAY 0.872340 (-1225 3225);
PAINT ORANGE (-1225 3225);
DISPLAY INVISIBLE (-1225 3225);
FORCEADD TAP..1
(-1550 3250);
FORCEPROP 3 LASTPIN (-1600 3250) SIG_NAME SATA6G_TX_DP<2>
J 0
(-1590 3260);
DISPLAY 0.659574 (-1590 3260);
PAINT MONO (-1590 3260);
DISPLAY INVISIBLE (-1590 3260);
FORCEPROP 1 LASTPIN (-1600 3250) BN 2
J 0
(-1612 3258);
DISPLAY 0.617021 (-1612 3258);
PAINT GREEN (-1612 3258);
FORCEPROP 1 LAST PATH I197
J 0
(-1552 3250);
DISPLAY 0.872340 (-1552 3250);
PAINT GREEN (-1552 3250);
DISPLAY INVISIBLE (-1552 3250);
FORCEPROP 2 LAST CDS_LIB mstr_standard
J 0
(-1550 3250);
PAINT ORANGE (-1550 3250);
DISPLAY INVISIBLE (-1550 3250);
FORCEPROP 1 LAST BODY_TYPE PLUMBING
J 0
(-1550 3300);
DISPLAY 0.872340 (-1550 3300);
PAINT GREEN (-1550 3300);
DISPLAY INVISIBLE (-1550 3300);
FORCEPROP 1 LAST HDL_TAP TRUE
J 0
(-1225 3125);
DISPLAY 0.872340 (-1225 3125);
PAINT ORANGE (-1225 3125);
DISPLAY INVISIBLE (-1225 3125);
FORCEADD TAP..1
(-1550 3150);
FORCEPROP 3 LASTPIN (-1600 3150) SIG_NAME SATA6G_TX_DP<1>
J 0
(-1590 3160);
DISPLAY 0.659574 (-1590 3160);
PAINT MONO (-1590 3160);
DISPLAY INVISIBLE (-1590 3160);
FORCEPROP 1 LASTPIN (-1600 3150) BN 1
J 0
(-1612 3158);
DISPLAY 0.617021 (-1612 3158);
PAINT GREEN (-1612 3158);
FORCEPROP 1 LAST HDL_TAP TRUE
J 0
(-1225 3025);
DISPLAY 0.872340 (-1225 3025);
PAINT ORANGE (-1225 3025);
DISPLAY INVISIBLE (-1225 3025);
FORCEPROP 2 LAST CDS_LIB mstr_standard
J 0
(-1550 3150);
PAINT ORANGE (-1550 3150);
DISPLAY INVISIBLE (-1550 3150);
FORCEPROP 1 LAST PATH I198
J 0
(-1552 3150);
DISPLAY 0.872340 (-1552 3150);
PAINT GREEN (-1552 3150);
DISPLAY INVISIBLE (-1552 3150);
FORCEPROP 1 LAST BODY_TYPE PLUMBING
J 0
(-1550 3200);
DISPLAY 0.872340 (-1550 3200);
PAINT GREEN (-1550 3200);
DISPLAY INVISIBLE (-1550 3200);
FORCEADD TAP..1
(-1550 3050);
FORCEPROP 3 LASTPIN (-1600 3050) SIG_NAME SATA6G_TX_DP<0>
J 0
(-1590 3060);
DISPLAY 0.659574 (-1590 3060);
PAINT MONO (-1590 3060);
DISPLAY INVISIBLE (-1590 3060);
FORCEPROP 1 LASTPIN (-1600 3050) BN 0
J 0
(-1612 3058);
DISPLAY 0.617021 (-1612 3058);
PAINT GREEN (-1612 3058);
FORCEPROP 1 LAST HDL_TAP TRUE
J 0
(-1225 2925);
DISPLAY 0.872340 (-1225 2925);
PAINT ORANGE (-1225 2925);
DISPLAY INVISIBLE (-1225 2925);
FORCEPROP 1 LAST PATH I199
J 0
(-1552 3050);
DISPLAY 0.872340 (-1552 3050);
PAINT GREEN (-1552 3050);
DISPLAY INVISIBLE (-1552 3050);
FORCEPROP 2 LAST CDS_LIB mstr_standard
J 0
(-1550 3050);
PAINT ORANGE (-1550 3050);
DISPLAY INVISIBLE (-1550 3050);
FORCEPROP 1 LAST BODY_TYPE PLUMBING
J 0
(-1550 3100);
DISPLAY 0.872340 (-1550 3100);
PAINT GREEN (-1550 3100);
DISPLAY INVISIBLE (-1550 3100);
FORCEADD TAP..1
(-1375 3100);
FORCEPROP 3 LASTPIN (-1425 3100) SIG_NAME SATA6G_TX_DN<1>
J 0
(-1415 3110);
DISPLAY 0.659574 (-1415 3110);
PAINT MONO (-1415 3110);
DISPLAY INVISIBLE (-1415 3110);
FORCEPROP 1 LASTPIN (-1425 3100) BN 1
J 0
(-1437 3108);
DISPLAY 0.617021 (-1437 3108);
PAINT GREEN (-1437 3108);
FORCEPROP 1 LAST HDL_TAP TRUE
J 0
(-1050 2975);
DISPLAY 0.872340 (-1050 2975);
PAINT ORANGE (-1050 2975);
DISPLAY INVISIBLE (-1050 2975);
FORCEPROP 2 LAST CDS_LIB mstr_standard
J 0
(-1375 3100);
PAINT ORANGE (-1375 3100);
DISPLAY INVISIBLE (-1375 3100);
FORCEPROP 1 LAST BODY_TYPE PLUMBING
J 0
(-1375 3150);
DISPLAY 0.872340 (-1375 3150);
PAINT GREEN (-1375 3150);
DISPLAY INVISIBLE (-1375 3150);
FORCEPROP 1 LAST PATH I200
J 0
(-1377 3100);
DISPLAY 0.872340 (-1377 3100);
PAINT GREEN (-1377 3100);
DISPLAY INVISIBLE (-1377 3100);
FORCEADD TAP..1
(-1375 3200);
FORCEPROP 3 LASTPIN (-1425 3200) SIG_NAME SATA6G_TX_DN<2>
J 0
(-1415 3210);
DISPLAY 0.659574 (-1415 3210);
PAINT MONO (-1415 3210);
DISPLAY INVISIBLE (-1415 3210);
FORCEPROP 1 LASTPIN (-1425 3200) BN 2
J 0
(-1437 3208);
DISPLAY 0.617021 (-1437 3208);
PAINT GREEN (-1437 3208);
FORCEPROP 2 LAST CDS_LIB mstr_standard
J 0
(-1375 3200);
PAINT ORANGE (-1375 3200);
DISPLAY INVISIBLE (-1375 3200);
FORCEPROP 1 LAST PATH I201
J 0
(-1377 3200);
DISPLAY 0.872340 (-1377 3200);
PAINT GREEN (-1377 3200);
DISPLAY INVISIBLE (-1377 3200);
FORCEPROP 1 LAST BODY_TYPE PLUMBING
J 0
(-1375 3250);
DISPLAY 0.872340 (-1375 3250);
PAINT GREEN (-1375 3250);
DISPLAY INVISIBLE (-1375 3250);
FORCEPROP 1 LAST HDL_TAP TRUE
J 0
(-1050 3075);
DISPLAY 0.872340 (-1050 3075);
PAINT ORANGE (-1050 3075);
DISPLAY INVISIBLE (-1050 3075);
FORCEADD TAP..1
(-1375 3300);
FORCEPROP 3 LASTPIN (-1425 3300) SIG_NAME SATA6G_TX_DN<3>
J 0
(-1415 3310);
DISPLAY 0.659574 (-1415 3310);
PAINT MONO (-1415 3310);
DISPLAY INVISIBLE (-1415 3310);
FORCEPROP 1 LASTPIN (-1425 3300) BN 3
J 0
(-1437 3308);
DISPLAY 0.617021 (-1437 3308);
PAINT GREEN (-1437 3308);
FORCEPROP 1 LAST PATH I202
J 0
(-1377 3300);
DISPLAY 0.872340 (-1377 3300);
PAINT GREEN (-1377 3300);
DISPLAY INVISIBLE (-1377 3300);
FORCEPROP 2 LAST CDS_LIB mstr_standard
J 0
(-1375 3300);
PAINT ORANGE (-1375 3300);
DISPLAY INVISIBLE (-1375 3300);
FORCEPROP 1 LAST BODY_TYPE PLUMBING
J 0
(-1375 3350);
DISPLAY 0.872340 (-1375 3350);
PAINT GREEN (-1375 3350);
DISPLAY INVISIBLE (-1375 3350);
FORCEPROP 1 LAST HDL_TAP TRUE
J 0
(-1050 3175);
DISPLAY 0.872340 (-1050 3175);
PAINT ORANGE (-1050 3175);
DISPLAY INVISIBLE (-1050 3175);
FORCEADD TAP..1
(-1375 3000);
FORCEPROP 3 LASTPIN (-1425 3000) SIG_NAME SATA6G_TX_DN<0>
J 0
(-1415 3010);
DISPLAY 0.659574 (-1415 3010);
PAINT MONO (-1415 3010);
DISPLAY INVISIBLE (-1415 3010);
FORCEPROP 1 LASTPIN (-1425 3000) BN 0
J 0
(-1437 3008);
DISPLAY 0.617021 (-1437 3008);
PAINT GREEN (-1437 3008);
FORCEPROP 1 LAST PATH I203
J 0
(-1377 3000);
DISPLAY 0.872340 (-1377 3000);
PAINT GREEN (-1377 3000);
DISPLAY INVISIBLE (-1377 3000);
FORCEPROP 2 LAST CDS_LIB mstr_standard
J 0
(-1375 3000);
PAINT ORANGE (-1375 3000);
DISPLAY INVISIBLE (-1375 3000);
FORCEPROP 1 LAST HDL_TAP TRUE
J 0
(-1050 2875);
DISPLAY 0.872340 (-1050 2875);
PAINT ORANGE (-1050 2875);
DISPLAY INVISIBLE (-1050 2875);
FORCEPROP 1 LAST BODY_TYPE PLUMBING
J 0
(-1375 3050);
DISPLAY 0.872340 (-1375 3050);
PAINT GREEN (-1375 3050);
DISPLAY INVISIBLE (-1375 3050);
FORCEADD OFFPAGE..2
(-1750 2450);
FORCEPROP 2 LAST $XR0 185 
J 0
(-1561 2450);
DISPLAY 0.638298 (-1561 2450);
PAINT MONO (-1561 2450);
DISPLAY INVISIBLE (-1561 2450);
FORCEPROP 1 LAST COMMENT_BODY TRUE
J 0
(-1795 2355);
DISPLAY 1.170213 (-1795 2355);
PAINT PEACH (-1795 2355);
DISPLAY INVISIBLE (-1795 2355);
FORCEPROP 2 LAST CDS_LIB mstr_standard
J 0
(-1750 2450);
PAINT ORANGE (-1750 2450);
DISPLAY INVISIBLE (-1750 2450);
FORCEPROP 2 LAST PATH I204
J 0
(-1550 2500);
DISPLAY 1.021277 (-1550 2500);
PAINT ORANGE (-1550 2500);
DISPLAY INVISIBLE (-1550 2500);
FORCEPROP 1 LAST OFFPAGE TRUE
J 0
(-1425 2325);
PAINT GREEN (-1425 2325);
DISPLAY INVISIBLE (-1425 2325);
FORCEADD OFFPAGE..2
(-1750 2400);
FORCEPROP 2 LAST $XR0 185 
J 0
(-1561 2400);
DISPLAY 0.638298 (-1561 2400);
PAINT MONO (-1561 2400);
FORCEPROP 1 LAST COMMENT_BODY TRUE
J 0
(-1795 2305);
DISPLAY 1.170213 (-1795 2305);
PAINT PEACH (-1795 2305);
DISPLAY INVISIBLE (-1795 2305);
FORCEPROP 2 LAST CDS_LIB mstr_standard
J 0
(-1750 2400);
PAINT ORANGE (-1750 2400);
DISPLAY INVISIBLE (-1750 2400);
FORCEPROP 2 LAST PATH I205
J 0
(-1550 2450);
DISPLAY 1.021277 (-1550 2450);
PAINT ORANGE (-1550 2450);
DISPLAY INVISIBLE (-1550 2450);
FORCEPROP 1 LAST OFFPAGE TRUE
J 0
(-1425 2275);
PAINT GREEN (-1425 2275);
DISPLAY INVISIBLE (-1425 2275);
FORCEADD OFFPAGE..2
(-1750 2350);
FORCEPROP 2 LAST $XR0 185 
J 0
(-1561 2350);
DISPLAY 0.638298 (-1561 2350);
PAINT MONO (-1561 2350);
FORCEPROP 1 LAST COMMENT_BODY TRUE
J 0
(-1795 2255);
DISPLAY 1.170213 (-1795 2255);
PAINT PEACH (-1795 2255);
DISPLAY INVISIBLE (-1795 2255);
FORCEPROP 2 LAST CDS_LIB mstr_standard
J 0
(-1750 2350);
PAINT ORANGE (-1750 2350);
DISPLAY INVISIBLE (-1750 2350);
FORCEPROP 2 LAST PATH I206
J 0
(-1550 2400);
DISPLAY 1.021277 (-1550 2400);
PAINT ORANGE (-1550 2400);
DISPLAY INVISIBLE (-1550 2400);
FORCEPROP 1 LAST OFFPAGE TRUE
J 0
(-1425 2225);
PAINT GREEN (-1425 2225);
DISPLAY INVISIBLE (-1425 2225);
FORCEADD OFFPAGE..2
(-1750 2500);
FORCEPROP 2 LAST $XR0 185 
J 0
(-1561 2500);
DISPLAY 0.638298 (-1561 2500);
PAINT MONO (-1561 2500);
FORCEPROP 1 LAST COMMENT_BODY TRUE
J 0
(-1795 2405);
DISPLAY 1.170213 (-1795 2405);
PAINT PEACH (-1795 2405);
DISPLAY INVISIBLE (-1795 2405);
FORCEPROP 2 LAST CDS_LIB mstr_standard
J 0
(-1750 2500);
PAINT ORANGE (-1750 2500);
DISPLAY INVISIBLE (-1750 2500);
FORCEPROP 2 LAST PATH I207
J 0
(-1550 2550);
DISPLAY 1.021277 (-1550 2550);
PAINT ORANGE (-1550 2550);
DISPLAY INVISIBLE (-1550 2550);
FORCEPROP 1 LAST OFFPAGE TRUE
J 0
(-1425 2375);
PAINT GREEN (-1425 2375);
DISPLAY INVISIBLE (-1425 2375);
FORCEADD OFFPAGE..2
(-1750 2200);
FORCEPROP 2 LAST $XR0 185 
J 0
(-1561 2200);
DISPLAY 0.638298 (-1561 2200);
PAINT MONO (-1561 2200);
FORCEPROP 1 LAST COMMENT_BODY TRUE
J 0
(-1795 2105);
DISPLAY 1.170213 (-1795 2105);
PAINT PEACH (-1795 2105);
DISPLAY INVISIBLE (-1795 2105);
FORCEPROP 2 LAST CDS_LIB mstr_standard
J 0
(-1750 2200);
PAINT ORANGE (-1750 2200);
DISPLAY INVISIBLE (-1750 2200);
FORCEPROP 2 LAST PATH I208
J 0
(-1575 2275);
DISPLAY 1.021277 (-1575 2275);
PAINT ORANGE (-1575 2275);
DISPLAY INVISIBLE (-1575 2275);
FORCEPROP 1 LAST OFFPAGE TRUE
J 0
(-1425 2075);
PAINT GREEN (-1425 2075);
DISPLAY INVISIBLE (-1425 2075);
FORCEADD OFFPAGE..2
(-1750 2150);
FORCEPROP 2 LAST $XR0 185 
J 0
(-1561 2150);
DISPLAY 0.638298 (-1561 2150);
PAINT MONO (-1561 2150);
FORCEPROP 1 LAST OFFPAGE TRUE
J 0
(-1425 2025);
PAINT GREEN (-1425 2025);
DISPLAY INVISIBLE (-1425 2025);
FORCEPROP 1 LAST COMMENT_BODY TRUE
J 0
(-1795 2055);
DISPLAY 1.170213 (-1795 2055);
PAINT PEACH (-1795 2055);
DISPLAY INVISIBLE (-1795 2055);
FORCEPROP 2 LAST CDS_LIB mstr_standard
J 0
(-1750 2150);
PAINT ORANGE (-1750 2150);
DISPLAY INVISIBLE (-1750 2150);
FORCEPROP 2 LAST PATH I209
J 0
(-1575 2225);
DISPLAY 1.021277 (-1575 2225);
PAINT ORANGE (-1575 2225);
DISPLAY INVISIBLE (-1575 2225);
FORCEADD OFFPAGE..2
(-1125 2950);
FORCEPROP 2 LAST $XR0 172 
J 0
(-936 2950);
DISPLAY 0.638298 (-936 2950);
PAINT MONO (-936 2950);
FORCEPROP 1 LAST COMMENT_BODY TRUE
J 0
(-1170 2855);
DISPLAY 1.170213 (-1170 2855);
PAINT PEACH (-1170 2855);
DISPLAY INVISIBLE (-1170 2855);
FORCEPROP 2 LAST CDS_LIB mstr_standard
J 0
(-1125 2950);
PAINT ORANGE (-1125 2950);
DISPLAY INVISIBLE (-1125 2950);
FORCEPROP 1 LAST OFFPAGE TRUE
J 0
(-800 2825);
PAINT GREEN (-800 2825);
DISPLAY INVISIBLE (-800 2825);
FORCEPROP 2 LAST PATH I21
J 0
(-950 3025);
DISPLAY 1.361702 (-950 3025);
PAINT ORANGE (-950 3025);
DISPLAY INVISIBLE (-950 3025);
FORCEADD OFFPAGE..2
(-1750 2250);
FORCEPROP 2 LAST $XR0 185 
J 0
(-1561 2250);
DISPLAY 0.638298 (-1561 2250);
PAINT MONO (-1561 2250);
FORCEPROP 1 LAST COMMENT_BODY TRUE
J 0
(-1795 2155);
DISPLAY 1.170213 (-1795 2155);
PAINT PEACH (-1795 2155);
DISPLAY INVISIBLE (-1795 2155);
FORCEPROP 2 LAST CDS_LIB mstr_standard
J 0
(-1750 2250);
PAINT ORANGE (-1750 2250);
DISPLAY INVISIBLE (-1750 2250);
FORCEPROP 2 LAST PATH I210
J 0
(-1575 2325);
DISPLAY 1.021277 (-1575 2325);
PAINT ORANGE (-1575 2325);
DISPLAY INVISIBLE (-1575 2325);
FORCEPROP 1 LAST OFFPAGE TRUE
J 0
(-1425 2125);
PAINT GREEN (-1425 2125);
DISPLAY INVISIBLE (-1425 2125);
FORCEADD OFFPAGE..2
(-1750 2300);
FORCEPROP 2 LAST $XR0 185 
J 0
(-1561 2300);
DISPLAY 0.638298 (-1561 2300);
PAINT MONO (-1561 2300);
FORCEPROP 1 LAST COMMENT_BODY TRUE
J 0
(-1795 2205);
DISPLAY 1.170213 (-1795 2205);
PAINT PEACH (-1795 2205);
DISPLAY INVISIBLE (-1795 2205);
FORCEPROP 2 LAST CDS_LIB mstr_standard
J 0
(-1750 2300);
PAINT ORANGE (-1750 2300);
DISPLAY INVISIBLE (-1750 2300);
FORCEPROP 2 LAST PATH I211
J 0
(-1575 2375);
DISPLAY 1.021277 (-1575 2375);
PAINT ORANGE (-1575 2375);
DISPLAY INVISIBLE (-1575 2375);
FORCEPROP 1 LAST OFFPAGE TRUE
J 0
(-1425 2175);
PAINT GREEN (-1425 2175);
DISPLAY INVISIBLE (-1425 2175);
FORCEADD OFFPAGE..1
(-6500 2250);
FORCEPROP 2 LAST $XR0 185 
J 0
(-6752 2250);
DISPLAY 0.638298 (-6752 2250);
PAINT MONO (-6752 2250);
FORCEPROP 2 LAST PATH I212
J 0
(-6775 2300);
DISPLAY 1.021277 (-6775 2300);
PAINT ORANGE (-6775 2300);
DISPLAY INVISIBLE (-6775 2300);
FORCEPROP 2 LAST CDS_LIB mstr_standard
J 0
(-6500 2250);
PAINT ORANGE (-6500 2250);
DISPLAY INVISIBLE (-6500 2250);
FORCEPROP 1 LAST COMMENT_BODY TRUE
J 0
(-6375 2150);
DISPLAY 1.170213 (-6375 2150);
PAINT PEACH (-6375 2150);
DISPLAY INVISIBLE (-6375 2150);
FORCEPROP 1 LAST OFFPAGE TRUE
J 0
(-6175 2125);
PAINT GREEN (-6175 2125);
DISPLAY INVISIBLE (-6175 2125);
FORCEADD OFFPAGE..1
(-6500 2200);
FORCEPROP 2 LAST $XR0 185 
J 0
(-6752 2200);
DISPLAY 0.638298 (-6752 2200);
PAINT MONO (-6752 2200);
FORCEPROP 2 LAST PATH I213
J 0
(-6775 2250);
DISPLAY 1.021277 (-6775 2250);
PAINT ORANGE (-6775 2250);
DISPLAY INVISIBLE (-6775 2250);
FORCEPROP 2 LAST CDS_LIB mstr_standard
J 0
(-6500 2200);
PAINT ORANGE (-6500 2200);
DISPLAY INVISIBLE (-6500 2200);
FORCEPROP 1 LAST COMMENT_BODY TRUE
J 0
(-6375 2100);
DISPLAY 1.170213 (-6375 2100);
PAINT PEACH (-6375 2100);
DISPLAY INVISIBLE (-6375 2100);
FORCEPROP 1 LAST OFFPAGE TRUE
J 0
(-6175 2075);
PAINT GREEN (-6175 2075);
DISPLAY INVISIBLE (-6175 2075);
FORCEADD OFFPAGE..1
(-6500 2150);
FORCEPROP 2 LAST $XR0 185 
J 0
(-6752 2150);
DISPLAY 0.638298 (-6752 2150);
PAINT MONO (-6752 2150);
FORCEPROP 1 LAST OFFPAGE TRUE
J 0
(-6175 2025);
PAINT GREEN (-6175 2025);
DISPLAY INVISIBLE (-6175 2025);
FORCEPROP 2 LAST PATH I214
J 0
(-6775 2200);
DISPLAY 1.021277 (-6775 2200);
PAINT ORANGE (-6775 2200);
DISPLAY INVISIBLE (-6775 2200);
FORCEPROP 2 LAST CDS_LIB mstr_standard
J 0
(-6500 2150);
PAINT ORANGE (-6500 2150);
DISPLAY INVISIBLE (-6500 2150);
FORCEPROP 1 LAST COMMENT_BODY TRUE
J 0
(-6375 2050);
DISPLAY 1.170213 (-6375 2050);
PAINT PEACH (-6375 2050);
DISPLAY INVISIBLE (-6375 2050);
FORCEADD OFFPAGE..1
(-6500 2350);
FORCEPROP 2 LAST $XR0 185 
J 0
(-6752 2350);
DISPLAY 0.638298 (-6752 2350);
PAINT MONO (-6752 2350);
FORCEPROP 2 LAST PATH I215
J 0
(-6775 2400);
DISPLAY 1.021277 (-6775 2400);
PAINT ORANGE (-6775 2400);
DISPLAY INVISIBLE (-6775 2400);
FORCEPROP 2 LAST CDS_LIB mstr_standard
J 0
(-6500 2350);
PAINT ORANGE (-6500 2350);
DISPLAY INVISIBLE (-6500 2350);
FORCEPROP 1 LAST COMMENT_BODY TRUE
J 0
(-6375 2250);
DISPLAY 1.170213 (-6375 2250);
PAINT PEACH (-6375 2250);
DISPLAY INVISIBLE (-6375 2250);
FORCEPROP 1 LAST OFFPAGE TRUE
J 0
(-6175 2225);
PAINT GREEN (-6175 2225);
DISPLAY INVISIBLE (-6175 2225);
FORCEADD OFFPAGE..1
(-6500 2400);
FORCEPROP 2 LAST $XR0 185 
J 0
(-6752 2400);
DISPLAY 0.638298 (-6752 2400);
PAINT MONO (-6752 2400);
FORCEPROP 2 LASTPIN (-6450 2400) SIG_NAME P3E_PCH_M2_RX_DP<2>
J 0
(-6450 2410);
DISPLAY 0.617021 (-6450 2410);
PAINT ORANGE (-6450 2410);
FORCEPROP 2 LAST PATH I216
J 0
(-6775 2450);
DISPLAY 1.021277 (-6775 2450);
PAINT ORANGE (-6775 2450);
DISPLAY INVISIBLE (-6775 2450);
FORCEPROP 2 LAST CDS_LIB mstr_standard
J 0
(-6500 2400);
PAINT ORANGE (-6500 2400);
DISPLAY INVISIBLE (-6500 2400);
FORCEPROP 1 LAST COMMENT_BODY TRUE
J 0
(-6375 2300);
DISPLAY 1.170213 (-6375 2300);
PAINT PEACH (-6375 2300);
DISPLAY INVISIBLE (-6375 2300);
FORCEPROP 1 LAST OFFPAGE TRUE
J 0
(-6175 2275);
PAINT GREEN (-6175 2275);
DISPLAY INVISIBLE (-6175 2275);
FORCEADD OFFPAGE..1
(-6500 2450);
FORCEPROP 2 LAST $XR0 185 
J 0
(-6752 2450);
DISPLAY 0.638298 (-6752 2450);
PAINT MONO (-6752 2450);
FORCEPROP 2 LASTPIN (-6450 2450) SIG_NAME P3E_PCH_M2_RX_DN<3>
J 0
(-6450 2460);
DISPLAY 0.617021 (-6450 2460);
PAINT ORANGE (-6450 2460);
FORCEPROP 2 LAST PATH I217
J 0
(-6775 2500);
DISPLAY 1.021277 (-6775 2500);
PAINT ORANGE (-6775 2500);
DISPLAY INVISIBLE (-6775 2500);
FORCEPROP 2 LAST CDS_LIB mstr_standard
J 0
(-6500 2450);
PAINT ORANGE (-6500 2450);
DISPLAY INVISIBLE (-6500 2450);
FORCEPROP 1 LAST COMMENT_BODY TRUE
J 0
(-6375 2350);
DISPLAY 1.170213 (-6375 2350);
PAINT PEACH (-6375 2350);
DISPLAY INVISIBLE (-6375 2350);
FORCEPROP 1 LAST OFFPAGE TRUE
J 0
(-6175 2325);
PAINT GREEN (-6175 2325);
DISPLAY INVISIBLE (-6175 2325);
FORCEADD OFFPAGE..1
(-6500 2500);
FORCEPROP 2 LAST $XR0 185 
J 0
(-6752 2500);
DISPLAY 0.638298 (-6752 2500);
PAINT MONO (-6752 2500);
FORCEPROP 2 LASTPIN (-6450 2500) SIG_NAME P3E_PCH_M2_RX_DP<3>
J 0
(-6450 2510);
DISPLAY 0.617021 (-6450 2510);
PAINT ORANGE (-6450 2510);
FORCEPROP 2 LAST PATH I218
J 0
(-6775 2550);
DISPLAY 1.021277 (-6775 2550);
PAINT ORANGE (-6775 2550);
DISPLAY INVISIBLE (-6775 2550);
FORCEPROP 2 LAST CDS_LIB mstr_standard
J 0
(-6500 2500);
PAINT ORANGE (-6500 2500);
DISPLAY INVISIBLE (-6500 2500);
FORCEPROP 1 LAST COMMENT_BODY TRUE
J 0
(-6375 2400);
DISPLAY 1.170213 (-6375 2400);
PAINT PEACH (-6375 2400);
DISPLAY INVISIBLE (-6375 2400);
FORCEPROP 1 LAST OFFPAGE TRUE
J 0
(-6175 2375);
PAINT GREEN (-6175 2375);
DISPLAY INVISIBLE (-6175 2375);
FORCEADD OFFPAGE..1
(-6500 2300);
FORCEPROP 2 LAST $XR0 185 
J 0
(-6752 2300);
DISPLAY 0.638298 (-6752 2300);
PAINT MONO (-6752 2300);
FORCEPROP 2 LAST PATH I219
J 0
(-6775 2350);
DISPLAY 1.021277 (-6775 2350);
PAINT ORANGE (-6775 2350);
DISPLAY INVISIBLE (-6775 2350);
FORCEPROP 2 LAST CDS_LIB mstr_standard
J 0
(-6500 2300);
PAINT ORANGE (-6500 2300);
DISPLAY INVISIBLE (-6500 2300);
FORCEPROP 1 LAST COMMENT_BODY TRUE
J 0
(-6375 2200);
DISPLAY 1.170213 (-6375 2200);
PAINT PEACH (-6375 2200);
DISPLAY INVISIBLE (-6375 2200);
FORCEPROP 1 LAST OFFPAGE TRUE
J 0
(-6175 2175);
PAINT GREEN (-6175 2175);
DISPLAY INVISIBLE (-6175 2175);
FORCEADD LBG_CORE_QAT_EXT_D..3
(-4025 2850);
FORCEPROP 2 LASTPIN (-5625 1800) $PN AF58
J 2
(-5635 1810);
DISPLAY 0.617021 (-5635 1810);
PAINT ORANGE (-5635 1810);
FORCEPROP 2 LASTPIN (-5625 1850) $PN AH58
J 2
(-5635 1860);
DISPLAY 0.617021 (-5635 1860);
PAINT ORANGE (-5635 1860);
FORCEPROP 2 LASTPIN (-5625 1700) $PN BD58
J 2
(-5635 1710);
DISPLAY 0.617021 (-5635 1710);
PAINT ORANGE (-5635 1710);
FORCEPROP 2 LASTPIN (-5625 1750) $PN BB56
J 2
(-5635 1760);
DISPLAY 0.617021 (-5635 1760);
PAINT ORANGE (-5635 1760);
FORCEPROP 2 LASTPIN (-5625 2000) $PN AP69
J 2
(-5635 2010);
DISPLAY 0.617021 (-5635 2010);
PAINT ORANGE (-5635 2010);
FORCEPROP 1 LAST PART_NUMBER H91415-002
J 0
(-5575 1500);
DISPLAY 0.617021 (-5575 1500);
PAINT BLUE (-5575 1500);
FORCEPROP 2 LASTPIN (-5625 2050) $PN AP71
J 2
(-5635 2060);
DISPLAY 0.617021 (-5635 2060);
PAINT ORANGE (-5635 2060);
FORCEPROP 2 LASTPIN (-5625 2400) $PN AW69
J 2
(-5635 2410);
DISPLAY 0.617021 (-5635 2410);
PAINT ORANGE (-5635 2410);
FORCEPROP 2 LASTPIN (-5625 2350) $PN AW71
J 2
(-5635 2360);
DISPLAY 0.617021 (-5635 2360);
PAINT ORANGE (-5635 2360);
FORCEPROP 2 LASTPIN (-5625 2300) $PN AY70
J 2
(-5635 2310);
DISPLAY 0.617021 (-5635 2310);
PAINT ORANGE (-5635 2310);
FORCEPROP 2 LASTPIN (-5625 2250) $PN AY72
J 2
(-5635 2260);
DISPLAY 0.617021 (-5635 2260);
PAINT ORANGE (-5635 2260);
FORCEPROP 2 LASTPIN (-5625 2200) $PN BA69
J 2
(-5635 2210);
DISPLAY 0.617021 (-5635 2210);
PAINT ORANGE (-5635 2210);
FORCEPROP 2 LASTPIN (-5625 2150) $PN BA71
J 2
(-5635 2160);
DISPLAY 0.617021 (-5635 2160);
PAINT ORANGE (-5635 2160);
FORCEPROP 2 LASTPIN (-5625 2500) $PN AV70
J 2
(-5635 2510);
DISPLAY 0.617021 (-5635 2510);
PAINT ORANGE (-5635 2510);
FORCEPROP 2 LASTPIN (-5625 2450) $PN AV72
J 2
(-5635 2460);
DISPLAY 0.617021 (-5635 2460);
PAINT ORANGE (-5635 2460);
FORCEPROP 2 LASTPIN (-5625 3000) $PN BA65
J 2
(-5635 3010);
DISPLAY 0.617021 (-5635 3010);
PAINT ORANGE (-5635 3010);
FORCEPROP 2 LASTPIN (-5625 2950) $PN BA61
J 2
(-5635 2960);
DISPLAY 0.617021 (-5635 2960);
PAINT ORANGE (-5635 2960);
FORCEPROP 2 LASTPIN (-5625 2900) $PN AY59
J 2
(-5635 2910);
DISPLAY 0.617021 (-5635 2910);
PAINT ORANGE (-5635 2910);
FORCEPROP 2 LASTPIN (-5625 2850) $PN BD61
J 2
(-5635 2860);
DISPLAY 0.617021 (-5635 2860);
PAINT ORANGE (-5635 2860);
FORCEPROP 2 LASTPIN (-5625 2800) $PN BB63
J 2
(-5635 2810);
DISPLAY 0.617021 (-5635 2810);
PAINT ORANGE (-5635 2810);
FORCEPROP 2 LASTPIN (-5625 2750) $PN AM71
J 2
(-5635 2760);
DISPLAY 0.617021 (-5635 2760);
PAINT ORANGE (-5635 2760);
FORCEPROP 2 LASTPIN (-5625 2700) $PN AM69
J 2
(-5635 2710);
DISPLAY 0.617021 (-5635 2710);
PAINT ORANGE (-5635 2710);
FORCEPROP 2 LASTPIN (-5625 2650) $PN AN72
J 2
(-5635 2660);
DISPLAY 0.617021 (-5635 2660);
PAINT ORANGE (-5635 2660);
FORCEPROP 2 LASTPIN (-5625 2600) $PN AN70
J 2
(-5635 2610);
DISPLAY 0.617021 (-5635 2610);
PAINT ORANGE (-5635 2610);
FORCEPROP 2 LASTPIN (-5625 3050) $PN BD65
J 2
(-5635 3060);
DISPLAY 0.617021 (-5635 3060);
PAINT ORANGE (-5635 3060);
FORCEPROP 2 LASTPIN (-5625 3350) $PN AV66
J 2
(-5635 3360);
DISPLAY 0.617021 (-5635 3360);
PAINT ORANGE (-5635 3360);
FORCEPROP 2 LASTPIN (-5625 3400) $PN AR61
J 2
(-5635 3410);
DISPLAY 0.617021 (-5635 3410);
PAINT ORANGE (-5635 3410);
FORCEPROP 2 LASTPIN (-5625 3450) $PN AT63
J 2
(-5635 3460);
DISPLAY 0.617021 (-5635 3460);
PAINT ORANGE (-5635 3460);
FORCEPROP 2 LASTPIN (-5625 3200) $PN AV63
J 2
(-5635 3210);
DISPLAY 0.617021 (-5635 3210);
PAINT ORANGE (-5635 3210);
FORCEPROP 2 LASTPIN (-5625 3250) $PN AU65
J 2
(-5635 3260);
DISPLAY 0.617021 (-5635 3260);
PAINT ORANGE (-5635 3260);
FORCEPROP 2 LASTPIN (-5625 3300) $PN AT66
J 2
(-5635 3310);
DISPLAY 0.617021 (-5635 3310);
PAINT ORANGE (-5635 3310);
FORCEPROP 2 LASTPIN (-5625 3150) $PN AY66
J 2
(-5635 3160);
DISPLAY 0.617021 (-5635 3160);
PAINT ORANGE (-5635 3160);
FORCEPROP 2 LASTPIN (-5625 3100) $PN AW65
J 2
(-5635 3110);
DISPLAY 0.617021 (-5635 3110);
PAINT ORANGE (-5635 3110);
FORCEPROP 2 LASTPIN (-5625 3500) $PN AL66
J 2
(-5635 3510);
DISPLAY 0.617021 (-5635 3510);
PAINT ORANGE (-5635 3510);
FORCEPROP 2 LASTPIN (-5625 3550) $PN AN65
J 2
(-5635 3560);
DISPLAY 0.617021 (-5635 3560);
PAINT ORANGE (-5635 3560);
FORCEPROP 2 LASTPIN (-5625 3900) $PN AH61
J 2
(-5635 3910);
DISPLAY 0.617021 (-5635 3910);
PAINT ORANGE (-5635 3910);
FORCEPROP 2 LASTPIN (-5625 3850) $PN AH65
J 2
(-5635 3860);
DISPLAY 0.617021 (-5635 3860);
PAINT ORANGE (-5635 3860);
FORCEPROP 2 LASTPIN (-5625 3800) $PN AF65
J 2
(-5635 3810);
DISPLAY 0.617021 (-5635 3810);
PAINT ORANGE (-5635 3810);
FORCEPROP 2 LASTPIN (-5625 3750) $PN AL63
J 2
(-5635 3760);
DISPLAY 0.617021 (-5635 3760);
PAINT ORANGE (-5635 3760);
FORCEPROP 2 LASTPIN (-5625 3700) $PN AP63
J 2
(-5635 3710);
DISPLAY 0.617021 (-5635 3710);
PAINT ORANGE (-5635 3710);
FORCEPROP 2 LASTPIN (-5625 3650) $PN AJ63
J 2
(-5635 3660);
DISPLAY 0.617021 (-5635 3660);
PAINT ORANGE (-5635 3660);
FORCEPROP 2 LASTPIN (-5625 3600) $PN AK65
J 2
(-5635 3610);
DISPLAY 0.617021 (-5635 3610);
PAINT ORANGE (-5635 3610);
FORCEPROP 2 LASTPIN (-5625 3950) $PN AG63
J 2
(-5635 3960);
DISPLAY 0.617021 (-5635 3960);
PAINT ORANGE (-5635 3960);
FORCEPROP 2 LASTPIN (-5625 4000) $PN AP59
J 2
(-5635 4010);
DISPLAY 0.617021 (-5635 4010);
PAINT ORANGE (-5635 4010);
FORCEPROP 2 LASTPIN (-5625 4050) $PN AN61
J 2
(-5635 4060);
DISPLAY 0.617021 (-5635 4060);
PAINT ORANGE (-5635 4060);
FORCEPROP 2 LASTPIN (-5625 4150) $PN AD61
J 2
(-5635 4160);
DISPLAY 0.617021 (-5635 4160);
PAINT ORANGE (-5635 4160);
FORCEPROP 2 LASTPIN (-5625 4100) $PN AA61
J 2
(-5635 4110);
DISPLAY 0.617021 (-5635 4110);
PAINT ORANGE (-5635 4110);
FORCEPROP 1 LAST MATERIAL IC
J 0
(-5575 4350);
DISPLAY 0.617021 (-5575 4350);
PAINT SKYBLUE (-5575 4350);
FORCEPROP 2 LASTPIN (-2425 1750) $PN E67
J 0
(-2415 1760);
DISPLAY 0.617021 (-2415 1760);
PAINT ORANGE (-2415 1760);
FORCEPROP 2 LASTPIN (-2425 1700) $PN D66
J 0
(-2415 1710);
DISPLAY 0.617021 (-2415 1710);
PAINT ORANGE (-2415 1710);
FORCEPROP 2 LASTPIN (-2425 2000) $PN G67
J 0
(-2415 2010);
DISPLAY 0.617021 (-2415 2010);
PAINT ORANGE (-2415 2010);
FORCEPROP 2 LASTPIN (-2425 1900) $PN AA71
J 0
(-2415 1910);
DISPLAY 0.617021 (-2415 1910);
PAINT ORANGE (-2415 1910);
FORCEPROP 2 LASTPIN (-2425 1850) $PN AA69
J 0
(-2415 1860);
DISPLAY 0.617021 (-2415 1860);
PAINT ORANGE (-2415 1860);
FORCEPROP 2 LASTPIN (-2425 2050) $PN H69
J 0
(-2415 2060);
DISPLAY 0.617021 (-2415 2060);
PAINT ORANGE (-2415 2060);
FORCEPROP 2 LASTPIN (-2425 2450) $PN BH61
J 0
(-2415 2460);
DISPLAY 0.617021 (-2415 2460);
PAINT ORANGE (-2415 2460);
FORCEPROP 2 LASTPIN (-2425 2500) $PN BK61
J 0
(-2415 2510);
DISPLAY 0.617021 (-2415 2510);
PAINT ORANGE (-2415 2510);
FORCEPROP 2 LASTPIN (-2425 2150) $PN BR61
J 0
(-2415 2160);
DISPLAY 0.617021 (-2415 2160);
PAINT ORANGE (-2415 2160);
FORCEPROP 2 LASTPIN (-2425 2200) $PN BN63
J 0
(-2415 2210);
DISPLAY 0.617021 (-2415 2210);
PAINT ORANGE (-2415 2210);
FORCEPROP 2 LASTPIN (-2425 2250) $PN BM65
J 0
(-2415 2260);
DISPLAY 0.617021 (-2415 2260);
PAINT ORANGE (-2415 2260);
FORCEPROP 2 LASTPIN (-2425 2300) $PN BR65
J 0
(-2415 2310);
DISPLAY 0.617021 (-2415 2310);
PAINT ORANGE (-2415 2310);
FORCEPROP 2 LASTPIN (-2425 2350) $PN BK65
J 0
(-2415 2360);
DISPLAY 0.617021 (-2415 2360);
PAINT ORANGE (-2415 2360);
FORCEPROP 2 LASTPIN (-2425 2400) $PN BL66
J 0
(-2415 2410);
DISPLAY 0.617021 (-2415 2410);
PAINT ORANGE (-2415 2410);
FORCEPROP 2 LASTPIN (-2425 2600) $PN BG66
J 0
(-2415 2610);
DISPLAY 0.617021 (-2415 2610);
PAINT ORANGE (-2415 2610);
FORCEPROP 2 LASTPIN (-2425 2650) $PN BJ66
J 0
(-2415 2660);
DISPLAY 0.617021 (-2415 2660);
PAINT ORANGE (-2415 2660);
FORCEPROP 2 LASTPIN (-2425 2700) $PN BH65
J 0
(-2415 2710);
DISPLAY 0.617021 (-2415 2710);
PAINT ORANGE (-2415 2710);
FORCEPROP 2 LASTPIN (-2425 2750) $PN BJ63
J 0
(-2415 2760);
DISPLAY 0.617021 (-2415 2760);
PAINT ORANGE (-2415 2760);
FORCEPROP 2 LASTPIN (-2425 2850) $PN AJ72
J 0
(-2415 2860);
DISPLAY 0.617021 (-2415 2860);
PAINT ORANGE (-2415 2860);
FORCEPROP 2 LASTPIN (-2425 2900) $PN AH69
J 0
(-2415 2910);
DISPLAY 0.617021 (-2415 2910);
PAINT ORANGE (-2415 2910);
FORCEPROP 2 LASTPIN (-2425 2950) $PN AH71
J 0
(-2415 2960);
DISPLAY 0.617021 (-2415 2960);
PAINT ORANGE (-2415 2960);
FORCEPROP 2 LASTPIN (-2425 3000) $PN AF70
J 0
(-2415 3010);
DISPLAY 0.617021 (-2415 3010);
PAINT ORANGE (-2415 3010);
FORCEPROP 2 LASTPIN (-2425 3050) $PN AF72
J 0
(-2415 3060);
DISPLAY 0.617021 (-2415 3060);
PAINT ORANGE (-2415 3060);
FORCEPROP 2 LASTPIN (-2425 3500) $PN V70
J 0
(-2415 3510);
DISPLAY 0.617021 (-2415 3510);
PAINT ORANGE (-2415 3510);
FORCEPROP 2 LASTPIN (-2425 3450) $PN W71
J 0
(-2415 3460);
DISPLAY 0.617021 (-2415 3460);
PAINT ORANGE (-2415 3460);
FORCEPROP 2 LASTPIN (-2425 3400) $PN W69
J 0
(-2415 3410);
DISPLAY 0.617021 (-2415 3410);
PAINT ORANGE (-2415 3410);
FORCEPROP 2 LASTPIN (-2425 3200) $PN AD70
J 0
(-2415 3210);
DISPLAY 0.617021 (-2415 3210);
PAINT ORANGE (-2415 3210);
FORCEPROP 2 LASTPIN (-2425 3250) $PN AD72
J 0
(-2415 3260);
DISPLAY 0.617021 (-2415 3260);
PAINT ORANGE (-2415 3260);
FORCEPROP 2 LASTPIN (-2425 3300) $PN AC69
J 0
(-2415 3310);
DISPLAY 0.617021 (-2415 3310);
PAINT ORANGE (-2415 3310);
FORCEPROP 2 LASTPIN (-2425 3350) $PN AC71
J 0
(-2415 3360);
DISPLAY 0.617021 (-2415 3360);
PAINT ORANGE (-2415 3360);
FORCEPROP 2 LASTPIN (-2425 3100) $PN AE69
J 0
(-2415 3110);
DISPLAY 0.617021 (-2415 3110);
PAINT ORANGE (-2415 3110);
FORCEPROP 2 LASTPIN (-2425 3150) $PN AE71
J 0
(-2415 3160);
DISPLAY 0.617021 (-2415 3160);
PAINT ORANGE (-2415 3160);
FORCEPROP 2 LASTPIN (-2425 3550) $PN V72
J 0
(-2415 3560);
DISPLAY 0.617021 (-2415 3560);
PAINT ORANGE (-2415 3560);
FORCEPROP 2 LASTPIN (-2425 3800) $PN P69
J 0
(-2415 3810);
DISPLAY 0.617021 (-2415 3810);
PAINT ORANGE (-2415 3810);
FORCEPROP 2 LASTPIN (-2425 3750) $PN R72
J 0
(-2415 3760);
DISPLAY 0.617021 (-2415 3760);
PAINT ORANGE (-2415 3760);
FORCEPROP 2 LASTPIN (-2425 3700) $PN R70
J 0
(-2415 3710);
DISPLAY 0.617021 (-2415 3710);
PAINT ORANGE (-2415 3710);
FORCEPROP 2 LASTPIN (-2425 3650) $PN T71
J 0
(-2415 3660);
DISPLAY 0.617021 (-2415 3660);
PAINT ORANGE (-2415 3660);
FORCEPROP 2 LASTPIN (-2425 3600) $PN T69
J 0
(-2415 3610);
DISPLAY 0.617021 (-2415 3610);
PAINT ORANGE (-2415 3610);
FORCEPROP 2 LASTPIN (-2425 4050) $PN M71
J 0
(-2415 4060);
DISPLAY 0.617021 (-2415 4060);
PAINT ORANGE (-2415 4060);
FORCEPROP 2 LASTPIN (-2425 4000) $PN M69
J 0
(-2415 4010);
DISPLAY 0.617021 (-2415 4010);
PAINT ORANGE (-2415 4010);
FORCEPROP 2 LASTPIN (-2425 3950) $PN N72
J 0
(-2415 3960);
DISPLAY 0.617021 (-2415 3960);
PAINT ORANGE (-2415 3960);
FORCEPROP 2 LASTPIN (-2425 3900) $PN N70
J 0
(-2415 3910);
DISPLAY 0.617021 (-2415 3910);
PAINT ORANGE (-2415 3910);
FORCEPROP 2 LASTPIN (-2425 3850) $PN P71
J 0
(-2415 3860);
DISPLAY 0.617021 (-2415 3860);
PAINT ORANGE (-2415 3860);
FORCEPROP 2 LASTPIN (-2425 4100) $PN L70
J 0
(-2415 4110);
DISPLAY 0.617021 (-2415 4110);
PAINT ORANGE (-2415 4110);
FORCEPROP 2 LASTPIN (-2425 4150) $PN L72
J 0
(-2415 4160);
DISPLAY 0.617021 (-2415 4160);
PAINT ORANGE (-2415 4160);
FORCEPROP 1 LAST LOCATION U7C1
J 0
(-5575 4450);
DISPLAY 0.617021 (-5575 4450);
PAINT AQUA (-5575 4450);
FORCEPROP 2 LASTPIN (-2425 2800) $PN AJ70
J 0
(-2415 2810);
DISPLAY 0.617021 (-2415 2810);
PAINT ORANGE (-2415 2810);
FORCEPROP 2 LAST SEC_TYPE BGA1
J 0
(-5575 4500);
DISPLAY 1.021277 (-5575 4500);
PAINT ORANGE (-5575 4500);
DISPLAY INVISIBLE (-5575 4500);
FORCEPROP 2 LAST SEC 3
J 0
(-5575 4500);
DISPLAY 0.680851 (-5575 4500);
PAINT MONO (-5575 4500);
DISPLAY INVISIBLE (-5575 4500);
FORCEPROP 0 LAST BOM_COST SB
J 0
(-5975 4900);
DISPLAY 1.361702 (-5975 4900);
PAINT ORANGE (-5975 4900);
DISPLAY INVISIBLE (-5975 4900);
FORCEPROP 2 LAST CDS_LOCATION U7C1
J 0
(-5575 4450);
DISPLAY 0.617021 (-5575 4450);
PAINT AQUA (-5575 4450);
DISPLAY INVISIBLE (-5575 4450);
FORCEPROP 0 LAST ROOM SB
J 0
(-5975 4800);
DISPLAY 1.361702 (-5975 4800);
PAINT ORANGE (-5975 4800);
DISPLAY INVISIBLE (-5975 4800);
FORCEPROP 1 LAST PACK_TYPE BGA1
J 0
(-5575 4450);
PAINT SKYBLUE (-5575 4450);
DISPLAY INVISIBLE (-5575 4450);
FORCEPROP 2 LAST CDS_LIB mstr_u_proc
J 0
(-4025 2850);
PAINT ORANGE (-4025 2850);
DISPLAY INVISIBLE (-4025 2850);
FORCEPROP 1 LAST PATH I220
J 0
(-4025 4350);
PAINT GREEN (-4025 4350);
DISPLAY INVISIBLE (-4025 4350);
FORCEADD OFFPAGE..2
(-925 4175);
FORCEPROP 2 LAST $XR0 173 
J 0
(-736 4175);
DISPLAY 0.638298 (-736 4175);
PAINT MONO (-736 4175);
FORCEPROP 1 LAST OFFPAGE TRUE
J 0
(-600 4050);
PAINT GREEN (-600 4050);
DISPLAY INVISIBLE (-600 4050);
FORCEPROP 1 LAST COMMENT_BODY TRUE
J 0
(-970 4080);
DISPLAY 1.170213 (-970 4080);
PAINT PEACH (-970 4080);
DISPLAY INVISIBLE (-970 4080);
FORCEPROP 2 LAST CDS_LIB mstr_standard
J 0
(-925 4175);
PAINT ORANGE (-925 4175);
DISPLAY INVISIBLE (-925 4175);
FORCEPROP 2 LAST PATH I221
J 0
(-750 4250);
DISPLAY 1.021277 (-750 4250);
PAINT ORANGE (-750 4250);
DISPLAY INVISIBLE (-750 4250);
FORCEADD OFFPAGE..2
(-925 4225);
FORCEPROP 2 LAST $XR0 173 
J 0
(-736 4225);
DISPLAY 0.638298 (-736 4225);
PAINT MONO (-736 4225);
FORCEPROP 1 LAST COMMENT_BODY TRUE
J 0
(-970 4130);
DISPLAY 1.170213 (-970 4130);
PAINT PEACH (-970 4130);
DISPLAY INVISIBLE (-970 4130);
FORCEPROP 2 LAST CDS_LIB mstr_standard
J 0
(-925 4225);
PAINT ORANGE (-925 4225);
DISPLAY INVISIBLE (-925 4225);
FORCEPROP 2 LAST PATH I222
J 0
(-750 4300);
DISPLAY 1.021277 (-750 4300);
PAINT ORANGE (-750 4300);
DISPLAY INVISIBLE (-750 4300);
FORCEPROP 1 LAST OFFPAGE TRUE
J 0
(-600 4100);
PAINT GREEN (-600 4100);
DISPLAY INVISIBLE (-600 4100);
FORCEADD OFFPAGE..1
(-7450 4250);
FORCEPROP 2 LAST $XR0 173 
J 0
(-7732 4250);
DISPLAY 0.638298 (-7732 4250);
PAINT MONO (-7732 4250);
FORCEPROP 2 LAST CDS_LIB mstr_standard
J 0
(-7450 4250);
PAINT ORANGE (-7450 4250);
DISPLAY INVISIBLE (-7450 4250);
FORCEPROP 2 LAST PATH I223
J 0
(-7400 4325);
DISPLAY 1.021277 (-7400 4325);
PAINT ORANGE (-7400 4325);
DISPLAY INVISIBLE (-7400 4325);
FORCEPROP 1 LAST COMMENT_BODY TRUE
J 0
(-7325 4150);
DISPLAY 1.170213 (-7325 4150);
PAINT PEACH (-7325 4150);
DISPLAY INVISIBLE (-7325 4150);
FORCEPROP 1 LAST OFFPAGE TRUE
J 0
(-7125 4125);
PAINT GREEN (-7125 4125);
DISPLAY INVISIBLE (-7125 4125);
FORCEADD OFFPAGE..1
(-7450 4300);
FORCEPROP 2 LAST $XR0 173 
J 0
(-7732 4300);
DISPLAY 0.638298 (-7732 4300);
PAINT MONO (-7732 4300);
FORCEPROP 2 LAST CDS_LIB mstr_standard
J 0
(-7450 4300);
PAINT ORANGE (-7450 4300);
DISPLAY INVISIBLE (-7450 4300);
FORCEPROP 2 LAST PATH I224
J 0
(-7400 4375);
DISPLAY 1.021277 (-7400 4375);
PAINT ORANGE (-7400 4375);
DISPLAY INVISIBLE (-7400 4375);
FORCEPROP 1 LAST COMMENT_BODY TRUE
J 0
(-7325 4200);
DISPLAY 1.170213 (-7325 4200);
PAINT PEACH (-7325 4200);
DISPLAY INVISIBLE (-7325 4200);
FORCEPROP 1 LAST OFFPAGE TRUE
J 0
(-7125 4175);
PAINT GREEN (-7125 4175);
DISPLAY INVISIBLE (-7125 4175);
FORCEADD OFFPAGE..1
(-7575 3400);
FORCEPROP 2 LAST $XR0 174 
J 0
(-7827 3400);
DISPLAY 0.638298 (-7827 3400);
PAINT MONO (-7827 3400);
FORCEPROP 1 LAST COMMENT_BODY TRUE
J 0
(-7450 3300);
DISPLAY 1.170213 (-7450 3300);
PAINT PEACH (-7450 3300);
DISPLAY INVISIBLE (-7450 3300);
FORCEPROP 2 LAST CDS_LIB mstr_standard
J 0
(-7575 3400);
PAINT ORANGE (-7575 3400);
DISPLAY INVISIBLE (-7575 3400);
FORCEPROP 2 LAST PATH I225
J 0
(-7525 3475);
DISPLAY 1.021277 (-7525 3475);
PAINT ORANGE (-7525 3475);
DISPLAY INVISIBLE (-7525 3475);
FORCEPROP 1 LAST OFFPAGE TRUE
J 0
(-7250 3275);
PAINT GREEN (-7250 3275);
DISPLAY INVISIBLE (-7250 3275);
FORCEADD OFFPAGE..1
(-7575 3450);
FORCEPROP 2 LAST $XR0 174 
J 0
(-7827 3450);
DISPLAY 0.638298 (-7827 3450);
PAINT MONO (-7827 3450);
FORCEPROP 2 LAST CDS_LIB mstr_standard
J 0
(-7575 3450);
PAINT ORANGE (-7575 3450);
DISPLAY INVISIBLE (-7575 3450);
FORCEPROP 2 LAST PATH I226
J 0
(-7525 3525);
DISPLAY 1.021277 (-7525 3525);
PAINT ORANGE (-7525 3525);
DISPLAY INVISIBLE (-7525 3525);
FORCEPROP 1 LAST COMMENT_BODY TRUE
J 0
(-7450 3350);
DISPLAY 1.170213 (-7450 3350);
PAINT PEACH (-7450 3350);
DISPLAY INVISIBLE (-7450 3350);
FORCEPROP 1 LAST OFFPAGE TRUE
J 0
(-7250 3325);
PAINT GREEN (-7250 3325);
DISPLAY INVISIBLE (-7250 3325);
FORCEADD OFFPAGE..2
(-825 3450);
FORCEPROP 2 LAST $XR0 174 
J 0
(-636 3450);
DISPLAY 0.638298 (-636 3450);
PAINT MONO (-636 3450);
FORCEPROP 1 LAST COMMENT_BODY TRUE
J 0
(-870 3355);
DISPLAY 1.170213 (-870 3355);
PAINT PEACH (-870 3355);
DISPLAY INVISIBLE (-870 3355);
FORCEPROP 2 LAST CDS_LIB mstr_standard
J 0
(-825 3450);
PAINT ORANGE (-825 3450);
DISPLAY INVISIBLE (-825 3450);
FORCEPROP 2 LAST PATH I227
J 0
(-650 3525);
DISPLAY 1.021277 (-650 3525);
PAINT ORANGE (-650 3525);
DISPLAY INVISIBLE (-650 3525);
FORCEPROP 1 LAST OFFPAGE TRUE
J 0
(-500 3325);
PAINT GREEN (-500 3325);
DISPLAY INVISIBLE (-500 3325);
FORCEADD OFFPAGE..2
(-825 3400);
FORCEPROP 2 LAST $XR0 174 
J 0
(-636 3400);
DISPLAY 0.638298 (-636 3400);
PAINT MONO (-636 3400);
FORCEPROP 1 LAST COMMENT_BODY TRUE
J 0
(-870 3305);
DISPLAY 1.170213 (-870 3305);
PAINT PEACH (-870 3305);
DISPLAY INVISIBLE (-870 3305);
FORCEPROP 2 LAST CDS_LIB mstr_standard
J 0
(-825 3400);
PAINT ORANGE (-825 3400);
DISPLAY INVISIBLE (-825 3400);
FORCEPROP 2 LAST PATH I228
J 0
(-650 3475);
DISPLAY 1.021277 (-650 3475);
PAINT ORANGE (-650 3475);
DISPLAY INVISIBLE (-650 3475);
FORCEPROP 1 LAST OFFPAGE TRUE
J 0
(-500 3275);
PAINT GREEN (-500 3275);
DISPLAY INVISIBLE (-500 3275);
FORCEADD RES..2
(-2125 1400);
FORCEPROP 1 LASTPIN (-2125 1300) $PN 2
J 0
(-2120 1310);
DISPLAY 0.617021 (-2120 1310);
PAINT ORANGE (-2120 1310);
FORCEPROP 1 LASTPIN (-2125 1500) $PN 1
J 0
(-2120 1462);
DISPLAY 0.617021 (-2120 1462);
PAINT ORANGE (-2120 1462);
FORCEPROP 1 LAST MATERIAL EMPTY
J 0
(-2085 1325);
DISPLAY 0.617021 (-2085 1325);
PAINT RED (-2085 1325);
FORCEPROP 1 LAST LOCATION R7B8
J 0
(-2080 1525);
DISPLAY 0.617021 (-2080 1525);
PAINT AQUA (-2080 1525);
FORCEPROP 1 LAST VALUE 10.0K
J 0
(-2080 1475);
DISPLAY 0.617021 (-2080 1475);
PAINT SKYBLUE (-2080 1475);
FORCEPROP 1 LAST TOLERANCE 1%
J 0
(-2080 1425);
DISPLAY 0.617021 (-2080 1425);
PAINT SKYBLUE (-2080 1425);
FORCEPROP 1 LAST PACK_TYPE 0402
J 0
(-2085 1225);
DISPLAY 0.617021 (-2085 1225);
PAINT SKYBLUE (-2085 1225);
FORCEPROP 1 LAST WATTAGE 1/16W
J 0
(-2085 1375);
DISPLAY 0.617021 (-2085 1375);
PAINT SKYBLUE (-2085 1375);
FORCEPROP 1 LAST PART_NUMBER G21796-016
J 0
(-2085 1275);
DISPLAY 0.617021 (-2085 1275);
PAINT BLUE (-2085 1275);
FORCEPROP 2 LAST CDS_LIB mstr_discrete
J 0
(-2125 1400);
PAINT ORANGE (-2125 1400);
DISPLAY INVISIBLE (-2125 1400);
FORCEPROP 2 LAST CDS_LOCATION R7B8
J 0
(-2080 1525);
DISPLAY 0.617021 (-2080 1525);
PAINT AQUA (-2080 1525);
DISPLAY INVISIBLE (-2080 1525);
FORCEPROP 1 LAST PATH I229
J 0
(-2075 1575);
DISPLAY 0.978723 (-2075 1575);
PAINT WHITE (-2075 1575);
DISPLAY INVISIBLE (-2075 1575);
FORCEPROP 2 LAST SEC_TYPE 0402
J 0
(-2075 1625);
DISPLAY 1.021277 (-2075 1625);
PAINT ORANGE (-2075 1625);
DISPLAY INVISIBLE (-2075 1625);
FORCEPROP 2 LAST SEC 1
J 0
(-2075 1625);
DISPLAY 0.680851 (-2075 1625);
PAINT MONO (-2075 1625);
DISPLAY INVISIBLE (-2075 1625);
FORCEPROP 2 LAST ROOM SB
J 0
(-2175 1550);
DISPLAY 1.617021 (-2175 1550);
PAINT WHITE (-2175 1550);
DISPLAY INVISIBLE (-2175 1550);
FORCEADD RES..2
(-1825 1400);
FORCEPROP 1 LASTPIN (-1825 1300) $PN 2
J 0
(-1820 1310);
DISPLAY 0.617021 (-1820 1310);
PAINT ORANGE (-1820 1310);
FORCEPROP 1 LASTPIN (-1825 1500) $PN 1
J 0
(-1820 1462);
DISPLAY 0.617021 (-1820 1462);
PAINT ORANGE (-1820 1462);
FORCEPROP 1 LAST PACK_TYPE 0402
J 0
(-1785 1225);
DISPLAY 0.617021 (-1785 1225);
PAINT SKYBLUE (-1785 1225);
FORCEPROP 1 LAST TOLERANCE 1%
J 0
(-1780 1425);
DISPLAY 0.617021 (-1780 1425);
PAINT SKYBLUE (-1780 1425);
FORCEPROP 1 LAST MATERIAL EMPTY
J 0
(-1785 1325);
DISPLAY 0.617021 (-1785 1325);
PAINT RED (-1785 1325);
FORCEPROP 1 LAST LOCATION R7B7
J 0
(-1780 1525);
DISPLAY 0.617021 (-1780 1525);
PAINT AQUA (-1780 1525);
FORCEPROP 1 LAST PART_NUMBER G21796-016
J 0
(-1785 1275);
DISPLAY 0.617021 (-1785 1275);
PAINT BLUE (-1785 1275);
FORCEPROP 1 LAST VALUE 10.0K
J 0
(-1780 1475);
DISPLAY 0.617021 (-1780 1475);
PAINT SKYBLUE (-1780 1475);
FORCEPROP 1 LAST WATTAGE 1/16W
J 0
(-1785 1375);
DISPLAY 0.617021 (-1785 1375);
PAINT SKYBLUE (-1785 1375);
FORCEPROP 2 LAST CDS_LIB mstr_discrete
J 0
(-1825 1400);
PAINT ORANGE (-1825 1400);
DISPLAY INVISIBLE (-1825 1400);
FORCEPROP 2 LAST CDS_LOCATION R7B7
J 0
(-1780 1525);
DISPLAY 0.617021 (-1780 1525);
PAINT AQUA (-1780 1525);
DISPLAY INVISIBLE (-1780 1525);
FORCEPROP 2 LAST ROOM SB
J 0
(-1875 1550);
DISPLAY 1.617021 (-1875 1550);
PAINT WHITE (-1875 1550);
DISPLAY INVISIBLE (-1875 1550);
FORCEPROP 2 LAST SEC 1
J 0
(-1775 1625);
DISPLAY 0.680851 (-1775 1625);
PAINT MONO (-1775 1625);
DISPLAY INVISIBLE (-1775 1625);
FORCEPROP 2 LAST SEC_TYPE 0402
J 0
(-1775 1625);
DISPLAY 1.021277 (-1775 1625);
PAINT ORANGE (-1775 1625);
DISPLAY INVISIBLE (-1775 1625);
FORCEPROP 1 LAST PATH I230
J 0
(-1775 1575);
DISPLAY 0.978723 (-1775 1575);
PAINT WHITE (-1775 1575);
DISPLAY INVISIBLE (-1775 1575);
FORCEADD GND..1
(-1925 1000);
FORCEPROP 3 LASTPIN (-1925 1050) SIG_NAME GND\g
J 0
(-1915 1060);
DISPLAY 0.659574 (-1915 1060);
PAINT MONO (-1915 1060);
DISPLAY INVISIBLE (-1915 1060);
FORCEPROP 1 LAST VOLTAGE 0.0V
J 0
(-1970 957);
DISPLAY 0.340426 (-1970 957);
PAINT SKYBLUE (-1970 957);
DISPLAY INVISIBLE (-1970 957);
FORCEPROP 1 LAST BODY_TYPE PLUMBING
J 0
(-1970 957);
DISPLAY 0.340426 (-1970 957);
PAINT GREEN (-1970 957);
DISPLAY INVISIBLE (-1970 957);
FORCEPROP 1 LAST SIZE 1B
J 0
(-1850 950);
DISPLAY 0.872340 (-1850 950);
PAINT AQUA (-1850 950);
DISPLAY INVISIBLE (-1850 950);
FORCEPROP 1 LAST PATH I231
J 0
(-1850 1000);
DISPLAY 0.872340 (-1850 1000);
PAINT AQUA (-1850 1000);
DISPLAY INVISIBLE (-1850 1000);
FORCEPROP 2 LAST CDS_LIB mstr_symbols
J 0
(-1925 1000);
PAINT ORANGE (-1925 1000);
DISPLAY INVISIBLE (-1925 1000);
FORCEPROP 1 LAST HDL_POWER GND
J 0
(-1925 1150);
DISPLAY 0.872340 (-1925 1150);
PAINT GREEN (-1925 1150);
DISPLAY INVISIBLE (-1925 1150);
FORCEADD OFFPAGE..1
(-6800 1050);
FORCEPROP 2 LAST $XR0 145 
J 0
(-7052 1050);
DISPLAY 0.638298 (-7052 1050);
PAINT MONO (-7052 1050);
FORCEPROP 2 LAST $XR1 116 
J 0
(-7172 1050);
DISPLAY 0.638298 (-7172 1050);
PAINT MONO (-7172 1050);
FORCEPROP 1 LAST COMMENT_BODY TRUE
J 0
(-6675 950);
DISPLAY 0.872340 (-6675 950);
PAINT GREEN (-6675 950);
DISPLAY INVISIBLE (-6675 950);
FORCEPROP 1 LAST OFFPAGE TRUE
J 0
(-6475 925);
DISPLAY 0.872340 (-6475 925);
PAINT GREEN (-6475 925);
DISPLAY INVISIBLE (-6475 925);
FORCEPROP 2 LAST PATH I232
J 0
(-6750 1125);
DISPLAY 1.021277 (-6750 1125);
PAINT ORANGE (-6750 1125);
DISPLAY INVISIBLE (-6750 1125);
FORCEPROP 2 LAST CDS_LIB mstr_standard
J 0
(-6800 1050);
PAINT ORANGE (-6800 1050);
DISPLAY INVISIBLE (-6800 1050);
FORCEADD OFFPAGE..1
(-6800 950);
FORCEPROP 2 LAST $XR0 145 
J 0
(-7052 950);
DISPLAY 0.638298 (-7052 950);
PAINT MONO (-7052 950);
FORCEPROP 2 LAST $XR1 116 
J 0
(-7172 950);
DISPLAY 0.638298 (-7172 950);
PAINT MONO (-7172 950);
FORCEPROP 1 LAST COMMENT_BODY TRUE
J 0
(-6675 850);
DISPLAY 0.872340 (-6675 850);
PAINT GREEN (-6675 850);
DISPLAY INVISIBLE (-6675 850);
FORCEPROP 2 LAST CDS_LIB mstr_standard
J 0
(-6800 950);
PAINT ORANGE (-6800 950);
DISPLAY INVISIBLE (-6800 950);
FORCEPROP 1 LAST OFFPAGE TRUE
J 0
(-6475 825);
DISPLAY 0.872340 (-6475 825);
PAINT GREEN (-6475 825);
DISPLAY INVISIBLE (-6475 825);
FORCEPROP 2 LAST PATH I233
J 0
(-6750 1025);
DISPLAY 1.021277 (-6750 1025);
PAINT ORANGE (-6750 1025);
DISPLAY INVISIBLE (-6750 1025);
FORCEADD RES..2
(-6225 725);
FORCEPROP 1 LAST LOCATION R3M9
J 0
(-6180 850);
DISPLAY 0.617021 (-6180 850);
PAINT AQUA (-6180 850);
FORCEPROP 1 LAST PART_NUMBER G21796-010
J 0
(-6185 600);
DISPLAY 0.617021 (-6185 600);
PAINT BLUE (-6185 600);
FORCEPROP 1 LAST VALUE 100.0K
J 0
(-6180 800);
DISPLAY 0.617021 (-6180 800);
PAINT SKYBLUE (-6180 800);
FORCEPROP 1 LAST TOLERANCE 1%
J 0
(-6180 750);
DISPLAY 0.617021 (-6180 750);
PAINT SKYBLUE (-6180 750);
FORCEPROP 1 LAST PACK_TYPE 0402
J 0
(-6185 550);
DISPLAY 0.617021 (-6185 550);
PAINT SKYBLUE (-6185 550);
FORCEPROP 1 LAST MATERIAL CHIP
J 0
(-6185 650);
DISPLAY 0.617021 (-6185 650);
PAINT SKYBLUE (-6185 650);
FORCEPROP 1 LAST WATTAGE 1/16W
J 0
(-6185 700);
DISPLAY 0.617021 (-6185 700);
PAINT SKYBLUE (-6185 700);
FORCEPROP 1 LASTPIN (-6225 625) $PN 2
J 0
(-6220 635);
DISPLAY 0.787234 (-6220 635);
PAINT ORANGE (-6220 635);
DISPLAY INVISIBLE (-6220 635);
FORCEPROP 2 LAST CDS_LIB mstr_discrete
J 0
(-6225 725);
PAINT ORANGE (-6225 725);
DISPLAY INVISIBLE (-6225 725);
FORCEPROP 1 LASTPIN (-6225 825) $PN 1
J 0
(-6220 787);
DISPLAY 0.787234 (-6220 787);
PAINT ORANGE (-6220 787);
DISPLAY INVISIBLE (-6220 787);
FORCEPROP 0 LAST ROOM SB
J 0
(-6175 950);
DISPLAY 1.021277 (-6175 950);
PAINT ORANGE (-6175 950);
DISPLAY INVISIBLE (-6175 950);
FORCEPROP 1 LAST PATH I234
J 0
(-6175 900);
DISPLAY 0.978723 (-6175 900);
PAINT WHITE (-6175 900);
DISPLAY INVISIBLE (-6175 900);
FORCEPROP 2 LAST CDS_SEC 1
J 0
(-6175 950);
PAINT MONO (-6175 950);
DISPLAY INVISIBLE (-6175 950);
FORCEPROP 2 LAST $SEC 1
J 0
(-6175 950);
PAINT MONO (-6175 950);
DISPLAY INVISIBLE (-6175 950);
FORCEPROP 2 LAST CDS_LOCATION R3M9
J 0
(-6180 850);
DISPLAY 0.617021 (-6180 850);
PAINT AQUA (-6180 850);
DISPLAY INVISIBLE (-6180 850);
FORCEADD RES..2
(-5900 725);
FORCEPROP 1 LAST MATERIAL CHIP
J 0
(-5860 650);
DISPLAY 0.617021 (-5860 650);
PAINT SKYBLUE (-5860 650);
FORCEPROP 1 LAST WATTAGE 1/16W
J 0
(-5860 700);
DISPLAY 0.617021 (-5860 700);
PAINT SKYBLUE (-5860 700);
FORCEPROP 1 LAST VALUE 100.0K
J 0
(-5855 800);
DISPLAY 0.617021 (-5855 800);
PAINT SKYBLUE (-5855 800);
FORCEPROP 1 LAST LOCATION R3M8
J 0
(-5855 850);
DISPLAY 0.617021 (-5855 850);
PAINT AQUA (-5855 850);
FORCEPROP 1 LAST PACK_TYPE 0402
J 0
(-5860 550);
DISPLAY 0.617021 (-5860 550);
PAINT SKYBLUE (-5860 550);
FORCEPROP 1 LAST TOLERANCE 1%
J 0
(-5855 750);
DISPLAY 0.617021 (-5855 750);
PAINT SKYBLUE (-5855 750);
FORCEPROP 1 LAST PART_NUMBER G21796-010
J 0
(-5860 600);
DISPLAY 0.617021 (-5860 600);
PAINT BLUE (-5860 600);
FORCEPROP 1 LASTPIN (-5900 625) $PN 2
J 0
(-5895 635);
DISPLAY 0.787234 (-5895 635);
PAINT ORANGE (-5895 635);
DISPLAY INVISIBLE (-5895 635);
FORCEPROP 1 LASTPIN (-5900 825) $PN 1
J 0
(-5895 787);
DISPLAY 0.787234 (-5895 787);
PAINT ORANGE (-5895 787);
DISPLAY INVISIBLE (-5895 787);
FORCEPROP 2 LAST CDS_LIB mstr_discrete
J 0
(-5900 725);
PAINT ORANGE (-5900 725);
DISPLAY INVISIBLE (-5900 725);
FORCEPROP 1 LAST PATH I235
J 0
(-5850 900);
DISPLAY 0.978723 (-5850 900);
PAINT WHITE (-5850 900);
DISPLAY INVISIBLE (-5850 900);
FORCEPROP 2 LAST CDS_LOCATION R3M8
J 0
(-5855 850);
DISPLAY 0.617021 (-5855 850);
PAINT AQUA (-5855 850);
DISPLAY INVISIBLE (-5855 850);
FORCEPROP 2 LAST $SEC 1
J 0
(-5850 950);
PAINT MONO (-5850 950);
DISPLAY INVISIBLE (-5850 950);
FORCEPROP 0 LAST ROOM SB
J 0
(-5850 950);
DISPLAY 1.021277 (-5850 950);
PAINT ORANGE (-5850 950);
DISPLAY INVISIBLE (-5850 950);
FORCEPROP 2 LAST CDS_SEC 1
J 0
(-5850 950);
PAINT MONO (-5850 950);
DISPLAY INVISIBLE (-5850 950);
FORCEADD GND..1
(-6225 400);
FORCEPROP 3 LASTPIN (-6225 450) SIG_NAME GND\g
J 0
(-6215 460);
DISPLAY 0.659574 (-6215 460);
PAINT MONO (-6215 460);
DISPLAY INVISIBLE (-6215 460);
FORCEPROP 1 LAST VOLTAGE 0.0V
J 0
(-6270 357);
DISPLAY 0.340426 (-6270 357);
PAINT SKYBLUE (-6270 357);
DISPLAY INVISIBLE (-6270 357);
FORCEPROP 1 LAST PATH I236
J 0
(-6150 400);
DISPLAY 0.872340 (-6150 400);
PAINT AQUA (-6150 400);
DISPLAY INVISIBLE (-6150 400);
FORCEPROP 1 LAST BODY_TYPE PLUMBING
J 0
(-6270 357);
DISPLAY 0.340426 (-6270 357);
PAINT GREEN (-6270 357);
DISPLAY INVISIBLE (-6270 357);
FORCEPROP 2 LAST CDS_LIB mstr_symbols
J 0
(-6225 400);
PAINT ORANGE (-6225 400);
DISPLAY INVISIBLE (-6225 400);
FORCEPROP 1 LAST SIZE 1B
J 0
(-6150 350);
DISPLAY 0.872340 (-6150 350);
PAINT AQUA (-6150 350);
DISPLAY INVISIBLE (-6150 350);
FORCEPROP 1 LAST HDL_POWER GND
J 0
(-6225 550);
DISPLAY 0.872340 (-6225 550);
PAINT GREEN (-6225 550);
DISPLAY INVISIBLE (-6225 550);
FORCEADD GND..1
(-5900 400);
FORCEPROP 3 LASTPIN (-5900 450) SIG_NAME GND\g
J 0
(-5890 460);
DISPLAY 0.659574 (-5890 460);
PAINT MONO (-5890 460);
DISPLAY INVISIBLE (-5890 460);
FORCEPROP 1 LAST VOLTAGE 0.0V
J 0
(-5945 357);
DISPLAY 0.340426 (-5945 357);
PAINT SKYBLUE (-5945 357);
DISPLAY INVISIBLE (-5945 357);
FORCEPROP 1 LAST PATH I237
J 0
(-5825 400);
DISPLAY 0.872340 (-5825 400);
PAINT AQUA (-5825 400);
DISPLAY INVISIBLE (-5825 400);
FORCEPROP 1 LAST BODY_TYPE PLUMBING
J 0
(-5945 357);
DISPLAY 0.340426 (-5945 357);
PAINT GREEN (-5945 357);
DISPLAY INVISIBLE (-5945 357);
FORCEPROP 2 LAST CDS_LIB mstr_symbols
J 0
(-5900 400);
PAINT ORANGE (-5900 400);
DISPLAY INVISIBLE (-5900 400);
FORCEPROP 1 LAST SIZE 1B
J 0
(-5825 350);
DISPLAY 0.872340 (-5825 350);
PAINT AQUA (-5825 350);
DISPLAY INVISIBLE (-5825 350);
FORCEPROP 1 LAST HDL_POWER GND
J 0
(-5900 550);
DISPLAY 0.872340 (-5900 550);
PAINT GREEN (-5900 550);
DISPLAY INVISIBLE (-5900 550);
FORCEADD OFFPAGE..2
(-1125 2700);
FORCEPROP 2 LAST $XR0 139 
J 0
(-936 2700);
DISPLAY 0.638298 (-936 2700);
PAINT MONO (-936 2700);
FORCEPROP 1 LAST COMMENT_BODY TRUE
J 0
(-1170 2605);
DISPLAY 1.170213 (-1170 2605);
PAINT PEACH (-1170 2605);
DISPLAY INVISIBLE (-1170 2605);
FORCEPROP 2 LAST CDS_LIB mstr_standard
J 0
(-1125 2700);
PAINT ORANGE (-1125 2700);
DISPLAY INVISIBLE (-1125 2700);
FORCEPROP 1 LAST OFFPAGE TRUE
J 0
(-800 2575);
PAINT GREEN (-800 2575);
DISPLAY INVISIBLE (-800 2575);
FORCEPROP 2 LAST PATH I26
J 0
(-950 2775);
DISPLAY 1.361702 (-950 2775);
PAINT ORANGE (-950 2775);
DISPLAY INVISIBLE (-950 2775);
FORCEADD OFFPAGE..2
(-1125 2750);
FORCEPROP 2 LAST $XR0 139 
J 0
(-936 2750);
DISPLAY 0.638298 (-936 2750);
PAINT MONO (-936 2750);
FORCEPROP 1 LAST COMMENT_BODY TRUE
J 0
(-1170 2655);
DISPLAY 1.170213 (-1170 2655);
PAINT PEACH (-1170 2655);
DISPLAY INVISIBLE (-1170 2655);
FORCEPROP 2 LAST CDS_LIB mstr_standard
J 0
(-1125 2750);
PAINT ORANGE (-1125 2750);
DISPLAY INVISIBLE (-1125 2750);
FORCEPROP 1 LAST OFFPAGE TRUE
J 0
(-800 2625);
PAINT GREEN (-800 2625);
DISPLAY INVISIBLE (-800 2625);
FORCEPROP 2 LAST PATH I27
J 0
(-950 2825);
DISPLAY 1.361702 (-950 2825);
PAINT ORANGE (-950 2825);
DISPLAY INVISIBLE (-950 2825);
FORCEADD OFFPAGE..2
(-1125 2800);
FORCEPROP 2 LAST $XR0 185 
J 0
(-936 2800);
DISPLAY 0.638298 (-936 2800);
PAINT MONO (-936 2800);
FORCEPROP 1 LAST COMMENT_BODY TRUE
J 0
(-1170 2705);
DISPLAY 1.170213 (-1170 2705);
PAINT PEACH (-1170 2705);
DISPLAY INVISIBLE (-1170 2705);
FORCEPROP 2 LAST CDS_LIB mstr_standard
J 0
(-1125 2800);
PAINT ORANGE (-1125 2800);
DISPLAY INVISIBLE (-1125 2800);
FORCEPROP 1 LAST OFFPAGE TRUE
J 0
(-800 2675);
PAINT GREEN (-800 2675);
DISPLAY INVISIBLE (-800 2675);
FORCEPROP 2 LAST PATH I28
J 0
(-950 2875);
DISPLAY 1.361702 (-950 2875);
PAINT ORANGE (-950 2875);
DISPLAY INVISIBLE (-950 2875);
FORCEADD OFFPAGE..2
(-1125 2850);
FORCEPROP 2 LAST $XR0 185 
J 0
(-936 2850);
DISPLAY 0.638298 (-936 2850);
PAINT MONO (-936 2850);
FORCEPROP 1 LAST COMMENT_BODY TRUE
J 0
(-1170 2755);
DISPLAY 1.170213 (-1170 2755);
PAINT PEACH (-1170 2755);
DISPLAY INVISIBLE (-1170 2755);
FORCEPROP 2 LAST CDS_LIB mstr_standard
J 0
(-1125 2850);
PAINT ORANGE (-1125 2850);
DISPLAY INVISIBLE (-1125 2850);
FORCEPROP 1 LAST OFFPAGE TRUE
J 0
(-800 2725);
PAINT GREEN (-800 2725);
DISPLAY INVISIBLE (-800 2725);
FORCEPROP 2 LAST PATH I29
J 0
(-950 2925);
DISPLAY 1.361702 (-950 2925);
PAINT ORANGE (-950 2925);
DISPLAY INVISIBLE (-950 2925);
FORCEADD OFFPAGE..2
(-1125 2900);
FORCEPROP 2 LAST $XR0 172 
J 0
(-936 2900);
DISPLAY 0.638298 (-936 2900);
PAINT MONO (-936 2900);
FORCEPROP 1 LAST COMMENT_BODY TRUE
J 0
(-1170 2805);
DISPLAY 1.170213 (-1170 2805);
PAINT PEACH (-1170 2805);
DISPLAY INVISIBLE (-1170 2805);
FORCEPROP 2 LAST CDS_LIB mstr_standard
J 0
(-1125 2900);
PAINT ORANGE (-1125 2900);
DISPLAY INVISIBLE (-1125 2900);
FORCEPROP 1 LAST OFFPAGE TRUE
J 0
(-800 2775);
PAINT GREEN (-800 2775);
DISPLAY INVISIBLE (-800 2775);
FORCEPROP 2 LAST PATH I30
J 0
(-950 2975);
DISPLAY 1.361702 (-950 2975);
PAINT ORANGE (-950 2975);
DISPLAY INVISIBLE (-950 2975);
FORCEADD OFFPAGE..2
(-450 2650);
FORCEPROP 2 LAST $XR0 145 
J 0
(-261 2650);
DISPLAY 0.638298 (-261 2650);
PAINT MONO (-261 2650);
FORCEPROP 1 LAST COMMENT_BODY TRUE
J 0
(-495 2555);
DISPLAY 1.170213 (-495 2555);
PAINT PEACH (-495 2555);
DISPLAY INVISIBLE (-495 2555);
FORCEPROP 1 LAST OFFPAGE TRUE
J 0
(-125 2525);
PAINT GREEN (-125 2525);
DISPLAY INVISIBLE (-125 2525);
FORCEPROP 2 LAST CDS_LIB mstr_standard
J 0
(-450 2650);
PAINT ORANGE (-450 2650);
DISPLAY INVISIBLE (-450 2650);
FORCEPROP 2 LAST PATH I31
J 0
(-275 2725);
DISPLAY 1.361702 (-275 2725);
PAINT ORANGE (-275 2725);
DISPLAY INVISIBLE (-275 2725);
FORCEADD OFFPAGE..2
(-450 2600);
FORCEPROP 2 LAST $XR0 145 
J 0
(-261 2600);
DISPLAY 0.638298 (-261 2600);
PAINT MONO (-261 2600);
FORCEPROP 1 LAST COMMENT_BODY TRUE
J 0
(-495 2505);
DISPLAY 1.170213 (-495 2505);
PAINT PEACH (-495 2505);
DISPLAY INVISIBLE (-495 2505);
FORCEPROP 1 LAST OFFPAGE TRUE
J 0
(-125 2475);
PAINT GREEN (-125 2475);
DISPLAY INVISIBLE (-125 2475);
FORCEPROP 2 LAST CDS_LIB mstr_standard
J 0
(-450 2600);
PAINT ORANGE (-450 2600);
DISPLAY INVISIBLE (-450 2600);
FORCEPROP 2 LAST PATH I32
J 0
(-275 2675);
DISPLAY 1.361702 (-275 2675);
PAINT ORANGE (-275 2675);
DISPLAY INVISIBLE (-275 2675);
FORCEADD OFFPAGE..1
(-7200 2950);
FORCEPROP 2 LAST $XR0 172 
J 0
(-7452 2950);
DISPLAY 0.638298 (-7452 2950);
PAINT MONO (-7452 2950);
FORCEPROP 2 LAST CDS_LIB mstr_standard
J 0
(-7200 2950);
PAINT ORANGE (-7200 2950);
DISPLAY INVISIBLE (-7200 2950);
FORCEPROP 1 LAST COMMENT_BODY TRUE
J 0
(-7075 2850);
DISPLAY 1.170213 (-7075 2850);
PAINT PEACH (-7075 2850);
DISPLAY INVISIBLE (-7075 2850);
FORCEPROP 1 LAST OFFPAGE TRUE
J 0
(-6875 2825);
PAINT GREEN (-6875 2825);
DISPLAY INVISIBLE (-6875 2825);
FORCEPROP 2 LAST PATH I97
J 0
(-7150 3025);
DISPLAY 1.361702 (-7150 3025);
PAINT ORANGE (-7150 3025);
DISPLAY INVISIBLE (-7150 3025);
FORCEADD DNS..2
(-1820 1395);
PAINT RED (-1820 1395);
FORCEPROP 1 LAST COMMENT_BODY TRUE
R 1
J 0
(-1745 1170);
DISPLAY 0.872340 (-1745 1170);
PAINT GREEN (-1745 1170);
DISPLAY INVISIBLE (-1745 1170);
FORCEPROP 2 LAST CDS_LIB mstr_misc
J 0
(-1820 1395);
PAINT ORANGE (-1820 1395);
DISPLAY INVISIBLE (-1820 1395);
FORCEADD DNS..2
(-1320 2595);
PAINT RED (-1320 2595);
FORCEPROP 1 LAST COMMENT_BODY TRUE
R 1
J 0
(-1245 2370);
DISPLAY 0.872340 (-1245 2370);
PAINT GREEN (-1245 2370);
DISPLAY INVISIBLE (-1245 2370);
FORCEPROP 2 LAST CDS_LIB mstr_misc
J 0
(-1320 2595);
PAINT ORANGE (-1320 2595);
DISPLAY INVISIBLE (-1320 2595);
FORCEADD CAD_NOTE..1
(-5500 1025);
FORCEPROP 0 LAST L1 PLACE PULL DOWNS NEAR PCH
J 0
(-5650 900);
DISPLAY 1.021277 (-5650 900);
PAINT WHITE (-5650 900);
FORCEPROP 1 LAST COMMENT_BODY TRUE
J 0
(-5475 1125);
DISPLAY 0.978723 (-5475 1125);
PAINT ORANGE (-5475 1125);
DISPLAY INVISIBLE (-5475 1125);
FORCEPROP 2 LAST CDS_LIB mstr_symbols
J 0
(-5500 1025);
PAINT ORANGE (-5500 1025);
DISPLAY INVISIBLE (-5500 1025);
FORCEADD CAD_NOTE..1
(-1000 2475);
FORCEPROP 0 LAST L1 PLACE BMC PCIE TX
J 0
(-1150 2350);
DISPLAY 0.808511 (-1150 2350);
PAINT ORANGE (-1150 2350);
FORCEPROP 0 LAST L2 CAPS CLOSE TO PCH
J 0
(-1150 2300);
DISPLAY 0.808511 (-1150 2300);
PAINT ORANGE (-1150 2300);
FORCEPROP 2 LAST CDS_LIB mstr_symbols
J 0
(-1000 2475);
PAINT ORANGE (-1000 2475);
DISPLAY INVISIBLE (-1000 2475);
FORCEPROP 1 LAST COMMENT_BODY TRUE
J 0
(-975 2575);
DISPLAY 0.978723 (-975 2575);
PAINT ORANGE (-975 2575);
DISPLAY INVISIBLE (-975 2575);
FORCEADD DESIGN_NOTE..1
(-5350 725);
FORCEPROP 0 LAST L1 PCIE ON AST1250 NOT USED. PULL DOWNS
J 0
(-5550 600);
DISPLAY 1.021277 (-5550 600);
PAINT ORANGE (-5550 600);
FORCEPROP 0 LAST L2 USED TO AVOID NOISE INTO LBG PINS
J 0
(-5550 525);
DISPLAY 1.021277 (-5550 525);
PAINT ORANGE (-5550 525);
FORCEPROP 0 LAST L3 IF AST2400 IS USED, UNSTUFF THESE RESISTORS
J 0
(-5550 450);
DISPLAY 1.021277 (-5550 450);
PAINT ORANGE (-5550 450);
FORCEPROP 1 LAST COMMENT_BODY TRUE
J 0
(-5325 825);
DISPLAY 0.978723 (-5325 825);
PAINT ORANGE (-5325 825);
DISPLAY INVISIBLE (-5325 825);
FORCEPROP 2 LAST CDS_LIB mstr_symbols
J 0
(-5350 725);
PAINT ORANGE (-5350 725);
DISPLAY INVISIBLE (-5350 725);
FORCEADD DNS..2
(-2120 1395);
PAINT RED (-2120 1395);
FORCEPROP 1 LAST COMMENT_BODY TRUE
R 1
J 0
(-2045 1170);
DISPLAY 0.872340 (-2045 1170);
PAINT GREEN (-2045 1170);
DISPLAY INVISIBLE (-2045 1170);
FORCEPROP 2 LAST CDS_LIB mstr_misc
J 0
(-2120 1395);
PAINT ORANGE (-2120 1395);
DISPLAY INVISIBLE (-2120 1395);
FORCEADD CAD_NOTE..1
(-7375 1525);
FORCEPROP 0 LAST L1 PLACE RCOMP RESISTORS WITHIN 2 INCHES OF PCH
J 0
(-7525 1400);
DISPLAY 1.021277 (-7525 1400);
PAINT WHITE (-7525 1400);
FORCEPROP 2 LAST CDS_LIB mstr_symbols
J 0
(-7375 1525);
PAINT ORANGE (-7375 1525);
DISPLAY INVISIBLE (-7375 1525);
FORCEPROP 1 LAST COMMENT_BODY TRUE
J 0
(-7350 1625);
DISPLAY 0.978723 (-7350 1625);
PAINT ORANGE (-7350 1625);
DISPLAY INVISIBLE (-7350 1625);
FORCEADD DNS..2
(-1720 2645);
PAINT RED (-1720 2645);
FORCEPROP 1 LAST COMMENT_BODY TRUE
R 1
J 0
(-1645 2420);
DISPLAY 0.872340 (-1645 2420);
PAINT GREEN (-1645 2420);
DISPLAY INVISIBLE (-1645 2420);
FORCEPROP 2 LAST CDS_LIB mstr_misc
J 0
(-1720 2645);
PAINT ORANGE (-1720 2645);
DISPLAY INVISIBLE (-1720 2645);
FORCEADD INTEL_CORP_BPAGE..1
(0 0);
FORCEPROP 1 LAST CDS_CON_LAST_MODIFIED Tue Dec 01 11:51:56 2015
J 0
(-1425 325);
DISPLAY 1.340426 (-1425 325);
PAINT ORANGE (-1425 325);
DISPLAY INVISIBLE (-1425 325);
FORCEPROP 1 LAST CUSTOM_TXT_CDS <CURRENT_DESIGN_SHEET> OF <TOTAL_DESIGN_SHEETS>
J 0
(-500 25);
PAINT GREEN (-500 25);
FORCEPROP 1 LAST CUSTOM_TXT_CDS <CON_LAST_MODIFIED>
J 0
(-1925 350);
PAINT GREEN (-1925 350);
FORCEPROP 2 LAST CUSTOM_TXT_CDS <XR_PAGE_TITLE>
J 0
(-7890 5250);
DISPLAY 0.638298 (-7890 5250);
PAINT PINK (-7890 5250);
DISPLAY INVISIBLE (-7890 5250);
FORCEPROP 1 LAST SCH_TITLE LEWISBURG 3/11 IO
J 0
(-7950 50);
DISPLAY 1.212766 (-7950 50);
PAINT YELLOW (-7950 50);
FORCEPROP 1 LAST SCH_ADDRESS3 Santa Clara, CA 95052-8119
J 0
(-3975 25);
DISPLAY 0.617021 (-3975 25);
PAINT YELLOW (-3975 25);
FORCEPROP 1 LAST SCH_ADDRESS2 P.O. BOX 58119
J 0
(-3975 75);
DISPLAY 0.617021 (-3975 75);
PAINT YELLOW (-3975 75);
FORCEPROP 1 LAST SCH_ADDRESS1 2200 Mission College Blvd.
J 0
(-3975 125);
DISPLAY 0.617021 (-3975 125);
PAINT YELLOW (-3975 125);
FORCEPROP 1 LAST SCH_NUMBER H4694802
J 0
(-1300 150);
DISPLAY 1.212766 (-1300 150);
PAINT YELLOW (-1300 150);
FORCEPROP 1 LAST SCH_DEPT BESD
J 1
(-4450 100);
DISPLAY 1.212766 (-4450 100);
PAINT YELLOW (-4450 100);
FORCEPROP 1 LAST SCH_REV 2.420
J 0
(-250 150);
DISPLAY 0.978723 (-250 150);
PAINT YELLOW (-250 150);
FORCEPROP 2 LAST PAGE_BORDER TRUE
J 0
(-7890 5250);
DISPLAY 0.851064 (-7890 5250);
PAINT PINK (-7890 5250);
DISPLAY INVISIBLE (-7890 5250);
FORCEPROP 2 LAST CDS_LIB mstr_symbols
J 0
(0 0);
PAINT ORANGE (0 0);
DISPLAY INVISIBLE (0 0);
FORCEPROP 1 LAST COMMENT_BODY TRUE
J 0
(12 12);
DISPLAY 0.638298 (12 12);
PAINT PEACH (12 12);
DISPLAY INVISIBLE (12 12);
FORCEPROP 2 LAST CDS_XR_PAGE_TITLE CR-116 : @BASEBOARD_FAB2_LIB.BASEBOARD_FAB2(SCH_1):PAGE116
J 0
(-7890 5250);
DISPLAY 0.638298 (-7890 5250);
PAINT PINK (-7890 5250);
DISPLAY INVISIBLE (-7890 5250);
WIRE 17 -1 (-6700 3175)(-6700 3275);
WIRE 17 -1 (-6700 3075)(-6700 3175);
WIRE 17 -1 (-6700 3275)(-6700 3375);
WIRE 17 -1 (-6700 3375)(-6700 3450);
WIRE 17 -1 (-6700 3450)(-7525 3450);
FORCEPROP 0 LAST SIG_NAME SATA6G_RX_DP<3:0>
J 0
(-7485 3460);
DISPLAY 0.617021 (-7485 3460);
PAINT ORANGE (-7485 3460);
WIRE 17 -1 (-6850 3125)(-6850 3225);
WIRE 17 -1 (-6850 3025)(-6850 3125);
WIRE 17 -1 (-6850 3225)(-6850 3325);
WIRE 17 -1 (-6850 3325)(-6850 3400);
WIRE 17 -1 (-6850 3400)(-7525 3400);
FORCEPROP 2 LAST SIG_NAME SATA6G_RX_DN<3:0>
J 0
(-7485 3410);
DISPLAY 0.617021 (-7485 3410);
PAINT ORANGE (-7485 3410);
WIRE 17 -1 (-6450 4175)(-6450 4075);
WIRE 17 -1 (-6450 4250)(-6450 4175);
WIRE 17 -1 (-6450 4075)(-6450 3975);
WIRE 17 -1 (-6450 3975)(-6450 3875);
WIRE 17 -1 (-7400 4250)(-6450 4250);
FORCEPROP 2 LAST SIG_NAME SATA6G_PCH_PCIE_UP_SATA_RXP<7:0>
J 0
(-7360 4260);
DISPLAY 0.617021 (-7360 4260);
PAINT ORANGE (-7360 4260);
WIRE 17 -1 (-6300 4125)(-6300 4025);
WIRE 17 -1 (-6300 4300)(-6300 4125);
WIRE 17 -1 (-6300 4025)(-6300 3925);
WIRE 17 -1 (-6300 3925)(-6300 3825);
WIRE 17 -1 (-7400 4300)(-6300 4300);
FORCEPROP 2 LAST SIG_NAME SATA6G_PCH_PCIE_UP_SATA_RXN<7:0>
J 0
(-7360 4310);
DISPLAY 0.617021 (-7360 4310);
PAINT ORANGE (-7360 4310);
WIRE 17 -1 (-6450 3875)(-6450 3775);
WIRE 17 -1 (-6300 3825)(-6300 3725);
WIRE 17 -1 (-6450 3775)(-6450 3675);
WIRE 17 -1 (-6450 3675)(-6450 3575);
WIRE 17 -1 (-6450 3575)(-6450 3475);
WIRE 17 -1 (-6300 3725)(-6300 3625);
WIRE 17 -1 (-6300 3625)(-6300 3525);
WIRE 17 -1 (-6300 3525)(-6300 3425);
WIRE 17 -1 (-1975 3675)(-1975 3575);
WIRE 17 -1 (-1975 3675)(-1975 3775);
WIRE 17 -1 (-1975 3575)(-1975 3475);
WIRE 17 -1 (-1975 3775)(-1975 3875);
WIRE 17 -1 (-1975 3875)(-1975 3975);
WIRE 17 -1 (-1975 3975)(-1975 4075);
WIRE 17 -1 (-1975 4075)(-1975 4175);
WIRE 17 -1 (-1975 4225)(-1975 4175);
WIRE 17 -1 (-1975 4225)(-975 4225);
FORCEPROP 2 LAST SIG_NAME SATA6G_PCH_PCIE_UP_SATA_TXP<7:0>
J 0
(-1785 4235);
DISPLAY 0.617021 (-1785 4235);
PAINT ORANGE (-1785 4235);
WIRE 17 -1 (-1500 3175)(-1500 3275);
WIRE 17 -1 (-1500 3075)(-1500 3175);
WIRE 17 -1 (-1500 3275)(-1500 3375);
WIRE 17 -1 (-1500 3375)(-1500 3450);
WIRE 17 -1 (-1500 3450)(-875 3450);
FORCEPROP 2 LAST SIG_NAME SATA6G_TX_DP<3:0>
J 0
(-1310 3460);
DISPLAY 0.617021 (-1310 3460);
PAINT ORANGE (-1310 3460);
WIRE 17 -1 (-1325 3125)(-1325 3225);
WIRE 17 -1 (-1325 3025)(-1325 3125);
WIRE 17 -1 (-1325 3225)(-1325 3325);
WIRE 17 -1 (-1325 3325)(-1325 3400);
FORCEPROP 2 LAST SIG_NAME SATA6G_TX_DN<3:0>
J 0
(-1310 3410);
DISPLAY 0.617021 (-1310 3410);
PAINT ORANGE (-1310 3410);
WIRE 17 -1 (-1825 4125)(-1825 4025);
WIRE 17 -1 (-1825 4175)(-1825 4125);
WIRE 17 -1 (-1825 4025)(-1825 3925);
WIRE 17 -1 (-1825 3825)(-1825 3925);
WIRE 17 -1 (-1825 4175)(-975 4175);
FORCEPROP 2 LAST SIG_NAME SATA6G_PCH_PCIE_UP_SATA_TXN<7:0>
J 0
(-1785 4185);
DISPLAY 0.617021 (-1785 4185);
PAINT ORANGE (-1785 4185);
WIRE 17 -1 (-1825 3725)(-1825 3825);
WIRE 17 -1 (-1825 3625)(-1825 3725);
WIRE 17 -1 (-1825 3525)(-1825 3625);
WIRE 17 -1 (-1825 3425)(-1825 3525);
WIRE 16 -1 (-1925 1150)(-2125 1150);
WIRE 16 -1 (-1825 1150)(-1925 1150);
WIRE 16 -1 (-1925 1150)(-1925 1050);
WIRE 16 -1 (-2125 1150)(-2125 1300);
WIRE 16 -1 (-1825 1300)(-1825 1150);
WIRE 16 -1 (-6225 450)(-6225 625);
WIRE 16 -1 (-5900 450)(-5900 625);
WIRE 17 -1 (-1325 3400)(-875 3400);
WIRE 16 -1 (-7150 2750)(-5625 2750);
FORCEPROP 0 LAST SIG_NAME PE_PCH_SPRV_RX_C_DP
J 0
(-7138 2760);
DISPLAY 0.617021 (-7138 2760);
PAINT ORANGE (-7138 2760);
WIRE 16 -1 (-2425 2150)(-1800 2150);
FORCEPROP 2 LAST SIG_NAME P3E_PCH_TX_0_DN
J 0
(-2260 2160);
DISPLAY 0.617021 (-2260 2160);
PAINT ORANGE (-2260 2160);
WIRE 16 -1 (-2425 2300)(-1800 2300);
FORCEPROP 2 LAST SIG_NAME P3E_PCH_M2_TX_DP<1>
J 0
(-2260 2310);
DISPLAY 0.617021 (-2260 2310);
PAINT ORANGE (-2260 2310);
WIRE 16 -1 (-2425 2600)(-1425 2600);
FORCEPROP 2 LAST SIG_NAME P2E_SSB_BMC_TX_DN
J 0
(-2310 2610);
DISPLAY 0.617021 (-2310 2610);
PAINT ORANGE (-2310 2610);
FORCEPROP 2 LASTPROP $XRERR UNIQUE?
J 0
(-2550 2610);
DISPLAY 0.638298 (-2550 2610);
PAINT MONO (-2550 2610);
DISPLAY INVISIBLE (-2550 2610);
WIRE 16 -1 (-6850 2050)(-5625 2050);
FORCEPROP 2 LAST SIG_NAME TP_PCH_RSVD48
J 0
(-6860 2060);
DISPLAY 0.617021 (-6860 2060);
PAINT ORANGE (-6860 2060);
FORCEPROP 2 LASTPROP $XRERR UNIQUE?
J 0
(-7090 2050);
DISPLAY 0.638298 (-7090 2050);
PAINT MONO (-7090 2050);
DISPLAY INVISIBLE (-7090 2050);
WIRE 16 -1 (-7450 1750)(-5625 1750);
FORCEPROP 0 LAST SIG_NAME A_PCIE_RCOMP_P
J 0
(-6978 1751);
DISPLAY 0.617021 (-6978 1751);
PAINT ORANGE (-6978 1751);
FORCEPROP 2 LASTPROP $XRERR UNIQUE?
J 0
(-7218 1751);
DISPLAY 0.638298 (-7218 1751);
PAINT MONO (-7218 1751);
DISPLAY INVISIBLE (-7218 1751);
WIRE 16 -1 (-7450 2300)(-7450 1750);
WIRE 16 -1 (-7450 2300)(-7550 2300);
WIRE 16 -1 (-7550 2250)(-7550 2300);
WIRE 16 -1 (-7125 1800)(-5625 1800);
FORCEPROP 0 LAST SIG_NAME A_PCIEUP_RCOMP_N
J 0
(-6978 1801);
DISPLAY 0.617021 (-6978 1801);
PAINT ORANGE (-6978 1801);
FORCEPROP 2 LASTPROP $XRERR UNIQUE?
J 0
(-7218 1801);
DISPLAY 0.638298 (-7218 1801);
PAINT MONO (-7218 1801);
DISPLAY INVISIBLE (-7218 1801);
WIRE 16 -1 (-7125 1800)(-7125 2050);
WIRE 16 -1 (-2425 4100)(-1925 4100);
WIRE 16 -1 (-2425 4150)(-2075 4150);
WIRE 16 -1 (-1625 2650)(-500 2650);
FORCEPROP 2 LAST SIG_NAME P2E_SSB_BMC_TX_C_DP
J 0
(-960 2660);
DISPLAY 0.617021 (-960 2660);
PAINT ORANGE (-960 2660);
WIRE 16 -1 (-500 2600)(-1225 2600);
FORCEPROP 2 LAST SIG_NAME P2E_SSB_BMC_TX_C_DN
J 0
(-960 2610);
DISPLAY 0.617021 (-960 2610);
PAINT ORANGE (-960 2610);
WIRE 16 -1 (-1825 1500)(-1825 1750);
WIRE 16 -1 (-2425 1750)(-1825 1750);
FORCEPROP 2 LAST SIG_NAME A_EXTCLKP
J 0
(-2285 1760);
DISPLAY 0.617021 (-2285 1760);
PAINT ORANGE (-2285 1760);
FORCEPROP 2 LASTPROP $XRERR UNIQUE?
J 0
(-2525 1760);
DISPLAY 0.638298 (-2525 1760);
PAINT MONO (-2525 1760);
DISPLAY INVISIBLE (-2525 1760);
WIRE 16 -1 (-2425 3200)(-1425 3200);
WIRE 16 -1 (-2425 3250)(-1600 3250);
WIRE 16 -1 (-2425 3300)(-1425 3300);
WIRE 16 -1 (-2425 3350)(-1600 3350);
WIRE 16 -1 (-2425 3400)(-1925 3400);
WIRE 16 -1 (-2425 3500)(-1925 3500);
WIRE 16 -1 (-2425 3600)(-1925 3600);
WIRE 16 -1 (-2425 3700)(-1925 3700);
WIRE 16 -1 (-2425 3800)(-1925 3800);
WIRE 16 -1 (-2425 3900)(-1925 3900);
WIRE 16 -1 (-2425 4000)(-1925 4000);
WIRE 16 -1 (-2425 3000)(-1425 3000);
WIRE 16 -1 (-2425 3050)(-1600 3050);
WIRE 16 -1 (-2425 3100)(-1425 3100);
WIRE 16 -1 (-2425 3150)(-1600 3150);
WIRE 16 -1 (-2425 1900)(-1950 1900);
FORCEPROP 2 LAST SIG_NAME TP_PCH_RSVD52
J 0
(-2260 1910);
DISPLAY 0.617021 (-2260 1910);
PAINT ORANGE (-2260 1910);
FORCEPROP 2 LASTPROP $XRERR UNIQUE?
J 0
(-1920 1900);
DISPLAY 0.638298 (-1920 1900);
PAINT MONO (-1920 1900);
DISPLAY INVISIBLE (-1920 1900);
WIRE 16 -1 (-2425 1850)(-1950 1850);
FORCEPROP 2 LAST SIG_NAME TP_PCH_RSVD51
J 0
(-2260 1860);
DISPLAY 0.617021 (-2260 1860);
PAINT ORANGE (-2260 1860);
FORCEPROP 2 LASTPROP $XRERR UNIQUE?
J 0
(-1920 1850);
DISPLAY 0.638298 (-1920 1850);
PAINT MONO (-1920 1850);
DISPLAY INVISIBLE (-1920 1850);
WIRE 16 -1 (-2425 2050)(-1950 2050);
FORCEPROP 2 LAST SIG_NAME TP_PCH_RSVD50
J 0
(-2260 2060);
DISPLAY 0.617021 (-2260 2060);
PAINT ORANGE (-2260 2060);
FORCEPROP 2 LASTPROP $XRERR UNIQUE?
J 0
(-1920 2050);
DISPLAY 0.638298 (-1920 2050);
PAINT MONO (-1920 2050);
DISPLAY INVISIBLE (-1920 2050);
WIRE 16 -1 (-2425 2000)(-1950 2000);
FORCEPROP 2 LAST SIG_NAME TP_PCH_RSVD49
J 0
(-2260 2010);
DISPLAY 0.617021 (-2260 2010);
PAINT ORANGE (-2260 2010);
FORCEPROP 2 LASTPROP $XRERR UNIQUE?
J 0
(-1920 2000);
DISPLAY 0.638298 (-1920 2000);
PAINT MONO (-1920 2000);
DISPLAY INVISIBLE (-1920 2000);
WIRE 16 -1 (-2425 2650)(-1825 2650);
FORCEPROP 2 LAST SIG_NAME P2E_SSB_BMC_TX_DP
J 0
(-2310 2660);
DISPLAY 0.617021 (-2310 2660);
PAINT ORANGE (-2310 2660);
FORCEPROP 2 LASTPROP $XRERR UNIQUE?
J 0
(-2550 2660);
DISPLAY 0.638298 (-2550 2660);
PAINT MONO (-2550 2660);
DISPLAY INVISIBLE (-2550 2660);
WIRE 16 -1 (-2425 2450)(-1800 2450);
FORCEPROP 2 LAST SIG_NAME P3E_PCH_M2_TX_DN<3>
J 0
(-2260 2460);
DISPLAY 0.617021 (-2260 2460);
PAINT ORANGE (-2260 2460);
WIRE 16 -1 (-2425 2400)(-1800 2400);
FORCEPROP 2 LAST SIG_NAME P3E_PCH_M2_TX_DP<2>
J 0
(-2260 2410);
DISPLAY 0.617021 (-2260 2410);
PAINT ORANGE (-2260 2410);
WIRE 16 -1 (-2425 2350)(-1800 2350);
FORCEPROP 2 LAST SIG_NAME P3E_PCH_M2_TX_DN<2>
J 0
(-2260 2360);
DISPLAY 0.617021 (-2260 2360);
PAINT ORANGE (-2260 2360);
WIRE 16 -1 (-2425 2500)(-1800 2500);
FORCEPROP 2 LAST SIG_NAME P3E_PCH_M2_TX_DP<3>
J 0
(-2260 2510);
DISPLAY 0.617021 (-2260 2510);
PAINT ORANGE (-2260 2510);
WIRE 16 -1 (-2425 2200)(-1800 2200);
FORCEPROP 2 LAST SIG_NAME P3E_PCH_TX_0_DP
J 0
(-2260 2210);
DISPLAY 0.617021 (-2260 2210);
PAINT ORANGE (-2260 2210);
WIRE 16 -1 (-2425 2950)(-1175 2950);
FORCEPROP 0 LAST SIG_NAME SATA6G_S1_TX_DP
J 2
(-1188 2960);
DISPLAY 0.617021 (-1188 2960);
PAINT ORANGE (-1188 2960);
WIRE 16 -1 (-1800 2250)(-2425 2250);
FORCEPROP 2 LAST SIG_NAME P3E_PCH_M2_TX_DN<1>
J 0
(-2260 2260);
DISPLAY 0.617021 (-2260 2260);
PAINT ORANGE (-2260 2260);
WIRE 16 -1 (-1175 2700)(-2425 2700);
FORCEPROP 0 LAST SIG_NAME PE_PCH_SPRV_TX_DN
J 2
(-1188 2710);
DISPLAY 0.617021 (-1188 2710);
PAINT ORANGE (-1188 2710);
WIRE 16 -1 (-2425 2750)(-1175 2750);
FORCEPROP 0 LAST SIG_NAME PE_PCH_SPRV_TX_DP
J 2
(-1188 2760);
DISPLAY 0.617021 (-1188 2760);
PAINT ORANGE (-1188 2760);
WIRE 16 -1 (-2425 2800)(-1175 2800);
FORCEPROP 0 LAST SIG_NAME SATA6G_S0_TX_DN
J 2
(-1188 2810);
DISPLAY 0.617021 (-1188 2810);
PAINT ORANGE (-1188 2810);
WIRE 16 -1 (-2425 2850)(-1175 2850);
FORCEPROP 0 LAST SIG_NAME SATA6G_S0_TX_DP
J 2
(-1188 2860);
DISPLAY 0.617021 (-1188 2860);
PAINT ORANGE (-1188 2860);
WIRE 16 -1 (-2425 2900)(-1175 2900);
FORCEPROP 0 LAST SIG_NAME SATA6G_S1_TX_DN
J 2
(-1188 2910);
DISPLAY 0.617021 (-1188 2910);
PAINT ORANGE (-1188 2910);
WIRE 16 -1 (-2425 3650)(-2075 3650);
WIRE 16 -1 (-2425 3750)(-2075 3750);
WIRE 16 -1 (-2425 3850)(-2075 3850);
WIRE 16 -1 (-2425 3950)(-2075 3950);
WIRE 16 -1 (-2425 4050)(-2075 4050);
WIRE 16 -1 (-2425 3450)(-2075 3450);
WIRE 16 -1 (-2425 3550)(-2075 3550);
WIRE 16 -1 (-2425 1700)(-2125 1700);
FORCEPROP 2 LAST SIG_NAME A_EXTCLKN
J 0
(-2285 1710);
DISPLAY 0.617021 (-2285 1710);
PAINT ORANGE (-2285 1710);
FORCEPROP 2 LASTPROP $XRERR UNIQUE?
J 0
(-2525 1710);
DISPLAY 0.638298 (-2525 1710);
PAINT MONO (-2525 1710);
DISPLAY INVISIBLE (-2525 1710);
WIRE 16 -1 (-2125 1700)(-2125 1500);
WIRE 16 -1 (-6200 4100)(-5625 4100);
WIRE 16 -1 (-6350 4150)(-5625 4150);
WIRE 16 -1 (-5900 825)(-5900 1050);
WIRE 16 -1 (-5900 1050)(-6750 1050);
FORCEPROP 2 LAST SIG_NAME P2E_SSB_BMC_RX_C_DP
J 0
(-6710 1060);
DISPLAY 0.617021 (-6710 1060);
PAINT ORANGE (-6710 1060);
WIRE 16 -1 (-7025 1850)(-5625 1850);
FORCEPROP 0 LAST SIG_NAME A_PCIEUP_RCOMP_P
J 0
(-6978 1851);
DISPLAY 0.617021 (-6978 1851);
PAINT ORANGE (-6978 1851);
FORCEPROP 2 LASTPROP $XRERR UNIQUE?
J 0
(-7218 1851);
DISPLAY 0.638298 (-7218 1851);
PAINT MONO (-7218 1851);
DISPLAY INVISIBLE (-7218 1851);
WIRE 16 -1 (-7025 2300)(-7025 1850);
WIRE 16 -1 (-7025 2300)(-7125 2300);
WIRE 16 -1 (-7125 2250)(-7125 2300);
WIRE 16 -1 (-6750 3200)(-5625 3200);
WIRE 16 -1 (-6600 3250)(-5625 3250);
WIRE 16 -1 (-6750 3300)(-5625 3300);
WIRE 16 -1 (-6600 3350)(-5625 3350);
WIRE 16 -1 (-6200 3400)(-5625 3400);
WIRE 16 -1 (-6350 3450)(-5625 3450);
WIRE 16 -1 (-6200 3500)(-5625 3500);
WIRE 16 -1 (-6350 3550)(-5625 3550);
WIRE 16 -1 (-6200 3600)(-5625 3600);
WIRE 16 -1 (-6350 3650)(-5625 3650);
WIRE 16 -1 (-6200 3700)(-5625 3700);
WIRE 16 -1 (-6350 3750)(-5625 3750);
WIRE 16 -1 (-6200 3800)(-5625 3800);
WIRE 16 -1 (-6350 3850)(-5625 3850);
WIRE 16 -1 (-6200 3900)(-5625 3900);
WIRE 16 -1 (-6350 3950)(-5625 3950);
WIRE 16 -1 (-6200 4000)(-5625 4000);
WIRE 16 -1 (-6350 4050)(-5625 4050);
WIRE 16 -1 (-6750 3000)(-5625 3000);
WIRE 16 -1 (-6600 3050)(-5625 3050);
WIRE 16 -1 (-6750 3100)(-5625 3100);
WIRE 16 -1 (-6600 3150)(-5625 3150);
WIRE 16 -1 (-7550 1700)(-5625 1700);
FORCEPROP 0 LAST SIG_NAME A_PCIE_RCOMP_N
J 0
(-6978 1701);
DISPLAY 0.617021 (-6978 1701);
PAINT ORANGE (-6978 1701);
FORCEPROP 2 LASTPROP $XRERR UNIQUE?
J 0
(-7218 1701);
DISPLAY 0.638298 (-7218 1701);
PAINT MONO (-7218 1701);
DISPLAY INVISIBLE (-7218 1701);
WIRE 16 -1 (-7550 1700)(-7550 2050);
WIRE 16 -1 (-6850 2000)(-5625 2000);
FORCEPROP 2 LAST SIG_NAME TP_PCH_RSVD47
J 0
(-6860 2010);
DISPLAY 0.617021 (-6860 2010);
PAINT ORANGE (-6860 2010);
FORCEPROP 2 LASTPROP $XRERR UNIQUE?
J 0
(-7090 2000);
DISPLAY 0.638298 (-7090 2000);
PAINT MONO (-7090 2000);
DISPLAY INVISIBLE (-7090 2000);
WIRE 16 -1 (-7150 2900)(-5625 2900);
FORCEPROP 0 LAST SIG_NAME SATA6G_S1_RX_DN
J 0
(-7138 2910);
DISPLAY 0.617021 (-7138 2910);
PAINT ORANGE (-7138 2910);
WIRE 16 -1 (-5625 2700)(-7150 2700);
FORCEPROP 0 LAST SIG_NAME PE_PCH_SPRV_RX_C_DN
J 0
(-7138 2710);
DISPLAY 0.617021 (-7138 2710);
PAINT ORANGE (-7138 2710);
WIRE 16 -1 (-7150 2850)(-5625 2850);
FORCEPROP 0 LAST SIG_NAME SATA6G_S0_RX_DP
J 0
(-7138 2860);
DISPLAY 0.617021 (-7138 2860);
PAINT ORANGE (-7138 2860);
WIRE 16 -1 (-7150 2800)(-5625 2800);
FORCEPROP 0 LAST SIG_NAME SATA6G_S0_RX_DN
J 0
(-7138 2810);
DISPLAY 0.617021 (-7138 2810);
PAINT ORANGE (-7138 2810);
WIRE 16 -1 (-7150 2650)(-5625 2650);
FORCEPROP 0 LAST SIG_NAME P2E_SSB_BMC_RX_C_DP
J 0
(-7138 2660);
DISPLAY 0.617021 (-7138 2660);
PAINT ORANGE (-7138 2660);
WIRE 16 -1 (-7150 2600)(-5625 2600);
FORCEPROP 0 LAST SIG_NAME P2E_SSB_BMC_RX_C_DN
J 0
(-7138 2610);
DISPLAY 0.617021 (-7138 2610);
PAINT ORANGE (-7138 2610);
WIRE 16 -1 (-5625 2250)(-6450 2250);
FORCEPROP 2 LAST SIG_NAME P3E_PCH_M2_RX_DN<1>
J 0
(-6450 2260);
DISPLAY 0.617021 (-6450 2260);
PAINT ORANGE (-6450 2260);
WIRE 16 -1 (-6450 2200)(-5625 2200);
FORCEPROP 2 LAST SIG_NAME P3E_PCH_RX_0_DP
J 0
(-6450 2210);
DISPLAY 0.617021 (-6450 2210);
PAINT ORANGE (-6450 2210);
WIRE 16 -1 (-6450 2150)(-5625 2150);
FORCEPROP 2 LAST SIG_NAME P3E_PCH_RX_0_DN
J 0
(-6450 2160);
DISPLAY 0.617021 (-6450 2160);
PAINT ORANGE (-6450 2160);
WIRE 16 -1 (-6450 2350)(-5625 2350);
FORCEPROP 2 LAST SIG_NAME P3E_PCH_M2_RX_DN<2>
J 0
(-6450 2360);
DISPLAY 0.617021 (-6450 2360);
PAINT ORANGE (-6450 2360);
WIRE 16 -1 (-6450 2400)(-5625 2400);
WIRE 16 -1 (-6450 2450)(-5625 2450);
WIRE 16 -1 (-6450 2500)(-5625 2500);
WIRE 16 -1 (-6450 2300)(-5625 2300);
FORCEPROP 2 LAST SIG_NAME P3E_PCH_M2_RX_DP<1>
J 0
(-6450 2310);
DISPLAY 0.617021 (-6450 2310);
PAINT ORANGE (-6450 2310);
WIRE 16 -1 (-7150 2950)(-5625 2950);
FORCEPROP 0 LAST SIG_NAME SATA6G_S1_RX_DP
J 0
(-7138 2960);
DISPLAY 0.617021 (-7138 2960);
PAINT ORANGE (-7138 2960);
WIRE 16 -1 (-6225 825)(-6225 950);
WIRE 16 -1 (-6225 950)(-6750 950);
FORCEPROP 2 LAST SIG_NAME P2E_SSB_BMC_RX_C_DN
J 0
(-6710 960);
DISPLAY 0.617021 (-6710 960);
PAINT ORANGE (-6710 960);
DOT 1 (-1925 1150);
FORCENOTE
MINI-SAS X8 VERTICAL
(-7650 4025) 0;
DISPLAY LEFT (-7650 4025);
DISPLAY 1.021277 (-7650 4025);
PAINT PURPLE (-7650 4025);
FORCENOTE
BMC
(-475 2475) 0;
DISPLAY LEFT (-475 2475);
DISPLAY 1.021277 (-475 2475);
PAINT PURPLE (-475 2475);
FORCENOTE
ROOM=SB
(-7900 250) 0;
DISPLAY LEFT (-7900 250);
DISPLAY 1.021277 (-7900 250);
PAINT PURPLE (-7900 250);
FORCENOTE
SPRV
(-7750 2725) 0;
DISPLAY LEFT (-7750 2725);
DISPLAY 1.021277 (-7750 2725);
PAINT PURPLE (-7750 2725);
FORCENOTE
BMC
(-7725 2600) 0;
DISPLAY LEFT (-7725 2600);
DISPLAY 1.021277 (-7725 2600);
PAINT PURPLE (-7725 2600);
FORCENOTE
SATA CONN
(-7950 2925) 0;
DISPLAY LEFT (-7950 2925);
DISPLAY 1.021277 (-7950 2925);
PAINT PURPLE (-7950 2925);
FORCENOTE
M.2 SATA
(-7875 2825) 0;
DISPLAY LEFT (-7875 2825);
DISPLAY 1.021277 (-7875 2825);
PAINT PURPLE (-7875 2825);
FORCENOTE
MINI-SAS
(-7700 3250) 0;
DISPLAY LEFT (-7700 3250);
DISPLAY 1.021277 (-7700 3250);
PAINT PURPLE (-7700 3250);
FORCENOTE
M.2 PCIE
(-7200 2400) 0;
DISPLAY LEFT (-7200 2400);
DISPLAY 1.021277 (-7200 2400);
PAINT PURPLE (-7200 2400);
FORCENOTE
MINI-SAS X8 VERTICAL
(-1075 3950) 0;
DISPLAY LEFT (-1075 3950);
DISPLAY 1.021277 (-1075 3950);
PAINT PURPLE (-1075 3950);
FORCENOTE
M.2 PCIE
(-1325 2200) 0;
DISPLAY LEFT (-1325 2200);
DISPLAY 1.021277 (-1325 2200);
PAINT PURPLE (-1325 2200);
FORCENOTE
SPRV
(-625 2750) 0;
DISPLAY LEFT (-625 2750);
DISPLAY 1.021277 (-625 2750);
PAINT PURPLE (-625 2750);
FORCENOTE
M.2 SATA
(-625 2825) 0;
DISPLAY LEFT (-625 2825);
DISPLAY 1.021277 (-625 2825);
PAINT PURPLE (-625 2825);
FORCENOTE
SATA CONN
(-625 2900) 0;
DISPLAY LEFT (-625 2900);
DISPLAY 1.021277 (-625 2900);
PAINT PURPLE (-625 2900);
FORCENOTE
MINI-SAS
(-825 3250) 0;
DISPLAY LEFT (-825 3250);
DISPLAY 1.021277 (-825 3250);
PAINT PURPLE (-825 3250);
QUIT
